FILE_TYPE = MACRO_DRAWING;
SET COLOR_WIRE YELLOW;
SET COLOR_PROP ORANGE;
SET COLOR_DOT WHITE;
SET COLOR_ARC YELLOW;
SET COLOR_BODY GREEN;
SET COLOR_NOTE PURPLE;
SET PROP_DISPLAY VALUE;
SET PAGE_NUMBER P13;
FORCEADD GENOA_SP5..4
(-4600 3650);
FORCEPROP 1 LAST LOCATION U25
J 0
(-5245 6481);
DISPLAY 0.489362 (-5245 6481);
PAINT SKYBLUE (-5245 6481);
FORCEPROP 0 LAST $SEC 4
J 0
(-5225 6525);
DISPLAY 0.680851 (-5225 6525);
PAINT MONO (-5225 6525);
DISPLAY INVISIBLE (-5225 6525);
FORCEPROP 0 LAST CDS_SEC 4
J 0
(-5250 6475);
DISPLAY 1.021277 (-5250 6475);
DISPLAY INVISIBLE (-5250 6475);
FORCEPROP 0 LASTPIN (-5400 3025) $PN BC60
J 2
(-5410 3035);
DISPLAY 0.489362 (-5410 3035);
PAINT MONO (-5410 3035);
FORCEPROP 0 LASTPIN (-5400 2975) $PN BD60
J 2
(-5410 2985);
DISPLAY 0.489362 (-5410 2985);
PAINT MONO (-5410 2985);
FORCEPROP 0 LASTPIN (-5400 1875) $PN BF60
J 2
(-5410 1885);
DISPLAY 0.489362 (-5410 1885);
PAINT MONO (-5410 1885);
FORCEPROP 0 LASTPIN (-5400 1825) $PN BG60
J 2
(-5410 1835);
DISPLAY 0.489362 (-5410 1835);
PAINT MONO (-5410 1835);
FORCEPROP 0 LASTPIN (-5400 2175) $PN AT58
J 2
(-5410 2185);
DISPLAY 0.489362 (-5410 2185);
PAINT MONO (-5410 2185);
FORCEPROP 0 LASTPIN (-5400 2075) $PN AU59
J 2
(-5410 2085);
DISPLAY 0.489362 (-5410 2085);
PAINT MONO (-5410 2085);
FORCEPROP 0 LASTPIN (-5400 2875) $PN AV60
J 2
(-5410 2885);
DISPLAY 0.489362 (-5410 2885);
PAINT MONO (-5410 2885);
FORCEPROP 0 LASTPIN (-5400 2825) $PN AW59
J 2
(-5410 2835);
DISPLAY 0.489362 (-5410 2835);
PAINT MONO (-5410 2835);
FORCEPROP 0 LASTPIN (-5400 2725) $PN BN59
J 2
(-5410 2735);
DISPLAY 0.489362 (-5410 2735);
PAINT MONO (-5410 2735);
FORCEPROP 0 LASTPIN (-5400 1725) $PN AU60
J 2
(-5410 1735);
DISPLAY 0.489362 (-5410 1735);
PAINT MONO (-5410 1735);
FORCEPROP 0 LASTPIN (-5400 1675) $PN AV58
J 2
(-5410 1685);
DISPLAY 0.489362 (-5410 1685);
PAINT MONO (-5410 1685);
FORCEPROP 0 LASTPIN (-5400 1575) $PN BP58
J 2
(-5410 1585);
DISPLAY 0.489362 (-5410 1585);
PAINT MONO (-5410 1585);
FORCEPROP 0 LASTPIN (-5400 3875) $PN AW60
J 2
(-5410 3885);
DISPLAY 0.489362 (-5410 3885);
PAINT MONO (-5410 3885);
FORCEPROP 0 LASTPIN (-5400 3825) $PN AY60
J 2
(-5410 3835);
DISPLAY 0.489362 (-5410 3835);
PAINT MONO (-5410 3835);
FORCEPROP 0 LASTPIN (-5400 3775) $PN AY58
J 2
(-5410 3785);
DISPLAY 0.489362 (-5410 3785);
PAINT MONO (-5410 3785);
FORCEPROP 0 LASTPIN (-5400 3725) $PN BA59
J 2
(-5410 3735);
DISPLAY 0.489362 (-5410 3735);
PAINT MONO (-5410 3735);
FORCEPROP 0 LASTPIN (-5400 3675) $PN BA60
J 2
(-5410 3685);
DISPLAY 0.489362 (-5410 3685);
PAINT MONO (-5410 3685);
FORCEPROP 0 LASTPIN (-5400 3625) $PN BB60
J 2
(-5410 3635);
DISPLAY 0.489362 (-5410 3635);
PAINT MONO (-5410 3635);
FORCEPROP 0 LASTPIN (-5400 3575) $PN BB58
J 2
(-5410 3585);
DISPLAY 0.489362 (-5410 3585);
PAINT MONO (-5410 3585);
FORCEPROP 0 LASTPIN (-3800 2425) $PN AJ60
J 0
(-3790 2435);
DISPLAY 0.489362 (-3790 2435);
PAINT MONO (-3790 2435);
FORCEPROP 0 LASTPIN (-3800 2375) $PN AK58
J 0
(-3790 2385);
DISPLAY 0.489362 (-3790 2385);
PAINT MONO (-3790 2385);
FORCEPROP 0 LASTPIN (-3800 2325) $PN AK60
J 0
(-3790 2335);
DISPLAY 0.489362 (-3790 2335);
PAINT MONO (-3790 2335);
FORCEPROP 0 LASTPIN (-3800 2275) $PN AL59
J 0
(-3790 2285);
DISPLAY 0.489362 (-3790 2285);
PAINT MONO (-3790 2285);
FORCEPROP 0 LASTPIN (-3800 2225) $PN AN60
J 0
(-3790 2235);
DISPLAY 0.489362 (-3790 2235);
PAINT MONO (-3790 2235);
FORCEPROP 0 LASTPIN (-3800 2175) $PN AP58
J 0
(-3790 2185);
DISPLAY 0.489362 (-3790 2185);
PAINT MONO (-3790 2185);
FORCEPROP 0 LASTPIN (-3800 2125) $PN AP60
J 0
(-3790 2135);
DISPLAY 0.489362 (-3790 2135);
PAINT MONO (-3790 2135);
FORCEPROP 0 LASTPIN (-3800 2075) $PN AR59
J 0
(-3790 2085);
DISPLAY 0.489362 (-3790 2085);
PAINT MONO (-3790 2085);
FORCEPROP 0 LASTPIN (-3800 6025) $PN E60
J 0
(-3790 6035);
DISPLAY 0.489362 (-3790 6035);
PAINT MONO (-3790 6035);
FORCEPROP 0 LASTPIN (-3800 5975) $PN F58
J 0
(-3790 5985);
DISPLAY 0.489362 (-3790 5985);
PAINT MONO (-3790 5985);
FORCEPROP 0 LASTPIN (-3800 5925) $PN F60
J 0
(-3790 5935);
DISPLAY 0.489362 (-3790 5935);
PAINT MONO (-3790 5935);
FORCEPROP 0 LASTPIN (-3800 5875) $PN G59
J 0
(-3790 5885);
DISPLAY 0.489362 (-3790 5885);
PAINT MONO (-3790 5885);
FORCEPROP 0 LASTPIN (-3800 5825) $PN J60
J 0
(-3790 5835);
DISPLAY 0.489362 (-3790 5835);
PAINT MONO (-3790 5835);
FORCEPROP 0 LASTPIN (-3800 5775) $PN K58
J 0
(-3790 5785);
DISPLAY 0.489362 (-3790 5785);
PAINT MONO (-3790 5785);
FORCEPROP 0 LASTPIN (-3800 5725) $PN K60
J 0
(-3790 5735);
DISPLAY 0.489362 (-3790 5735);
PAINT MONO (-3790 5735);
FORCEPROP 0 LASTPIN (-3800 5675) $PN L59
J 0
(-3790 5685);
DISPLAY 0.489362 (-3790 5685);
PAINT MONO (-3790 5685);
FORCEPROP 0 LASTPIN (-3800 5575) $PN L60
J 0
(-3790 5585);
DISPLAY 0.489362 (-3790 5585);
PAINT MONO (-3790 5585);
FORCEPROP 0 LASTPIN (-3800 5525) $PN M58
J 0
(-3790 5535);
DISPLAY 0.489362 (-3790 5535);
PAINT MONO (-3790 5535);
FORCEPROP 0 LASTPIN (-3800 5475) $PN M60
J 0
(-3790 5485);
DISPLAY 0.489362 (-3790 5485);
PAINT MONO (-3790 5485);
FORCEPROP 0 LASTPIN (-3800 5425) $PN N59
J 0
(-3790 5435);
DISPLAY 0.489362 (-3790 5435);
PAINT MONO (-3790 5435);
FORCEPROP 0 LASTPIN (-3800 5375) $PN R60
J 0
(-3790 5385);
DISPLAY 0.489362 (-3790 5385);
PAINT MONO (-3790 5385);
FORCEPROP 0 LASTPIN (-3800 5325) $PN T58
J 0
(-3790 5335);
DISPLAY 0.489362 (-3790 5335);
PAINT MONO (-3790 5335);
FORCEPROP 0 LASTPIN (-3800 5275) $PN T60
J 0
(-3790 5285);
DISPLAY 0.489362 (-3790 5285);
PAINT MONO (-3790 5285);
FORCEPROP 0 LASTPIN (-3800 5225) $PN U59
J 0
(-3790 5235);
DISPLAY 0.489362 (-3790 5235);
PAINT MONO (-3790 5235);
FORCEPROP 0 LASTPIN (-3800 5125) $PN U60
J 0
(-3790 5135);
DISPLAY 0.489362 (-3790 5135);
PAINT MONO (-3790 5135);
FORCEPROP 0 LASTPIN (-3800 5075) $PN V58
J 0
(-3790 5085);
DISPLAY 0.489362 (-3790 5085);
PAINT MONO (-3790 5085);
FORCEPROP 0 LASTPIN (-3800 5025) $PN V60
J 0
(-3790 5035);
DISPLAY 0.489362 (-3790 5035);
PAINT MONO (-3790 5035);
FORCEPROP 0 LASTPIN (-3800 4975) $PN W59
J 0
(-3790 4985);
DISPLAY 0.489362 (-3790 4985);
PAINT MONO (-3790 4985);
FORCEPROP 0 LASTPIN (-3800 4925) $PN AA60
J 0
(-3790 4935);
DISPLAY 0.489362 (-3790 4935);
PAINT MONO (-3790 4935);
FORCEPROP 0 LASTPIN (-3800 4875) $PN AB58
J 0
(-3790 4885);
DISPLAY 0.489362 (-3790 4885);
PAINT MONO (-3790 4885);
FORCEPROP 0 LASTPIN (-3800 4825) $PN AB60
J 0
(-3790 4835);
DISPLAY 0.489362 (-3790 4835);
PAINT MONO (-3790 4835);
FORCEPROP 0 LASTPIN (-3800 4775) $PN AC59
J 0
(-3790 4785);
DISPLAY 0.489362 (-3790 4785);
PAINT MONO (-3790 4785);
FORCEPROP 0 LASTPIN (-3800 4675) $PN AC60
J 0
(-3790 4685);
DISPLAY 0.489362 (-3790 4685);
PAINT MONO (-3790 4685);
FORCEPROP 0 LASTPIN (-3800 4625) $PN AD58
J 0
(-3790 4635);
DISPLAY 0.489362 (-3790 4635);
PAINT MONO (-3790 4635);
FORCEPROP 0 LASTPIN (-3800 4575) $PN AD60
J 0
(-3790 4585);
DISPLAY 0.489362 (-3790 4585);
PAINT MONO (-3790 4585);
FORCEPROP 0 LASTPIN (-3800 4525) $PN AE59
J 0
(-3790 4535);
DISPLAY 0.489362 (-3790 4535);
PAINT MONO (-3790 4535);
FORCEPROP 0 LASTPIN (-3800 4475) $PN AG60
J 0
(-3790 4485);
DISPLAY 0.489362 (-3790 4485);
PAINT MONO (-3790 4485);
FORCEPROP 0 LASTPIN (-3800 4425) $PN AH58
J 0
(-3790 4435);
DISPLAY 0.489362 (-3790 4435);
PAINT MONO (-3790 4435);
FORCEPROP 0 LASTPIN (-3800 4375) $PN AH60
J 0
(-3790 4385);
DISPLAY 0.489362 (-3790 4385);
PAINT MONO (-3790 4385);
FORCEPROP 0 LASTPIN (-3800 4325) $PN AJ59
J 0
(-3790 4335);
DISPLAY 0.489362 (-3790 4335);
PAINT MONO (-3790 4335);
FORCEPROP 0 LASTPIN (-5400 6025) $PN G60
J 2
(-5410 6035);
DISPLAY 0.489362 (-5410 6035);
PAINT MONO (-5410 6035);
FORCEPROP 0 LASTPIN (-5400 5925) $PN N60
J 2
(-5410 5935);
DISPLAY 0.489362 (-5410 5935);
PAINT MONO (-5410 5935);
FORCEPROP 0 LASTPIN (-5400 5825) $PN W60
J 2
(-5410 5835);
DISPLAY 0.489362 (-5410 5835);
PAINT MONO (-5410 5835);
FORCEPROP 0 LASTPIN (-5400 5725) $PN AE60
J 2
(-5410 5735);
DISPLAY 0.489362 (-5410 5735);
PAINT MONO (-5410 5735);
FORCEPROP 0 LASTPIN (-5400 5625) $PN AL60
J 2
(-5410 5635);
DISPLAY 0.489362 (-5410 5635);
PAINT MONO (-5410 5635);
FORCEPROP 0 LASTPIN (-5400 5525) $PN J59
J 2
(-5410 5535);
DISPLAY 0.489362 (-5410 5535);
PAINT MONO (-5410 5535);
FORCEPROP 0 LASTPIN (-5400 5425) $PN R59
J 2
(-5410 5435);
DISPLAY 0.489362 (-5410 5435);
PAINT MONO (-5410 5435);
FORCEPROP 0 LASTPIN (-5400 5325) $PN AA59
J 2
(-5410 5335);
DISPLAY 0.489362 (-5410 5335);
PAINT MONO (-5410 5335);
FORCEPROP 0 LASTPIN (-5400 5225) $PN AG59
J 2
(-5410 5235);
DISPLAY 0.489362 (-5410 5235);
PAINT MONO (-5410 5235);
FORCEPROP 0 LASTPIN (-5400 5125) $PN AN59
J 2
(-5410 5135);
DISPLAY 0.489362 (-5410 5135);
PAINT MONO (-5410 5135);
FORCEPROP 0 LASTPIN (-5400 5975) $PN H60
J 2
(-5410 5985);
DISPLAY 0.489362 (-5410 5985);
PAINT MONO (-5410 5985);
FORCEPROP 0 LASTPIN (-5400 5875) $PN P60
J 2
(-5410 5885);
DISPLAY 0.489362 (-5410 5885);
PAINT MONO (-5410 5885);
FORCEPROP 0 LASTPIN (-5400 5775) $PN Y60
J 2
(-5410 5785);
DISPLAY 0.489362 (-5410 5785);
PAINT MONO (-5410 5785);
FORCEPROP 0 LASTPIN (-5400 5675) $PN AF60
J 2
(-5410 5685);
DISPLAY 0.489362 (-5410 5685);
PAINT MONO (-5410 5685);
FORCEPROP 0 LASTPIN (-5400 5575) $PN AM60
J 2
(-5410 5585);
DISPLAY 0.489362 (-5410 5585);
PAINT MONO (-5410 5585);
FORCEPROP 0 LASTPIN (-5400 5475) $PN H58
J 2
(-5410 5485);
DISPLAY 0.489362 (-5410 5485);
PAINT MONO (-5410 5485);
FORCEPROP 0 LASTPIN (-5400 5375) $PN P58
J 2
(-5410 5385);
DISPLAY 0.489362 (-5410 5385);
PAINT MONO (-5410 5385);
FORCEPROP 0 LASTPIN (-5400 5275) $PN Y58
J 2
(-5410 5285);
DISPLAY 0.489362 (-5410 5285);
PAINT MONO (-5410 5285);
FORCEPROP 0 LASTPIN (-5400 5175) $PN AF58
J 2
(-5410 5185);
DISPLAY 0.489362 (-5410 5185);
PAINT MONO (-5410 5185);
FORCEPROP 0 LASTPIN (-5400 5075) $PN AM58
J 2
(-5410 5085);
DISPLAY 0.489362 (-5410 5085);
PAINT MONO (-5410 5085);
FORCEPROP 0 LASTPIN (-5400 2625) $PN BC59
J 2
(-5410 2635);
DISPLAY 0.489362 (-5410 2635);
PAINT MONO (-5410 2635);
FORCEPROP 0 LASTPIN (-5400 2525) $PN BM58
J 2
(-5410 2535);
DISPLAY 0.489362 (-5410 2535);
PAINT MONO (-5410 2535);
FORCEPROP 0 LASTPIN (-5400 2475) $PN BN60
J 2
(-5410 2485);
DISPLAY 0.489362 (-5410 2485);
PAINT MONO (-5410 2485);
FORCEPROP 0 LASTPIN (-5400 2375) $PN BP60
J 2
(-5410 2385);
DISPLAY 0.489362 (-5410 2385);
PAINT MONO (-5410 2385);
FORCEPROP 0 LASTPIN (-5400 1475) $PN BL59
J 2
(-5410 1485);
DISPLAY 0.489362 (-5410 1485);
PAINT MONO (-5410 1485);
FORCEPROP 0 LASTPIN (-5400 1425) $PN BM60
J 2
(-5410 1435);
DISPLAY 0.489362 (-5410 1435);
PAINT MONO (-5410 1435);
FORCEPROP 0 LASTPIN (-5400 1325) $PN BR60
J 2
(-5410 1335);
DISPLAY 0.489362 (-5410 1335);
PAINT MONO (-5410 1335);
FORCEPROP 0 LASTPIN (-5400 3475) $PN BG59
J 2
(-5410 3485);
DISPLAY 0.489362 (-5410 3485);
PAINT MONO (-5410 3485);
FORCEPROP 0 LASTPIN (-5400 3425) $PN BH58
J 2
(-5410 3435);
DISPLAY 0.489362 (-5410 3435);
PAINT MONO (-5410 3435);
FORCEPROP 0 LASTPIN (-5400 3375) $PN BH60
J 2
(-5410 3385);
DISPLAY 0.489362 (-5410 3385);
PAINT MONO (-5410 3385);
FORCEPROP 0 LASTPIN (-5400 3325) $PN BJ60
J 2
(-5410 3335);
DISPLAY 0.489362 (-5410 3335);
PAINT MONO (-5410 3335);
FORCEPROP 0 LASTPIN (-5400 3275) $PN BJ59
J 2
(-5410 3285);
DISPLAY 0.489362 (-5410 3285);
PAINT MONO (-5410 3285);
FORCEPROP 0 LASTPIN (-5400 3225) $PN BK58
J 2
(-5410 3235);
DISPLAY 0.489362 (-5410 3235);
PAINT MONO (-5410 3235);
FORCEPROP 0 LASTPIN (-5400 3175) $PN BK60
J 2
(-5410 3185);
DISPLAY 0.489362 (-5410 3185);
PAINT MONO (-5410 3185);
FORCEPROP 0 LASTPIN (-3800 1975) $PN BY60
J 0
(-3790 1985);
DISPLAY 0.489362 (-3790 1985);
PAINT MONO (-3790 1985);
FORCEPROP 0 LASTPIN (-3800 1925) $PN CA59
J 0
(-3790 1935);
DISPLAY 0.489362 (-3790 1935);
PAINT MONO (-3790 1935);
FORCEPROP 0 LASTPIN (-3800 1875) $PN CA60
J 0
(-3790 1885);
DISPLAY 0.489362 (-3790 1885);
PAINT MONO (-3790 1885);
FORCEPROP 0 LASTPIN (-3800 1825) $PN CB58
J 0
(-3790 1835);
DISPLAY 0.489362 (-3790 1835);
PAINT MONO (-3790 1835);
FORCEPROP 0 LASTPIN (-3800 1775) $PN BT60
J 0
(-3790 1785);
DISPLAY 0.489362 (-3790 1785);
PAINT MONO (-3790 1785);
FORCEPROP 0 LASTPIN (-3800 1725) $PN BU59
J 0
(-3790 1735);
DISPLAY 0.489362 (-3790 1735);
PAINT MONO (-3790 1735);
FORCEPROP 0 LASTPIN (-3800 1675) $PN BU60
J 0
(-3790 1685);
DISPLAY 0.489362 (-3790 1685);
PAINT MONO (-3790 1685);
FORCEPROP 0 LASTPIN (-3800 1625) $PN BV58
J 0
(-3790 1635);
DISPLAY 0.489362 (-3790 1635);
PAINT MONO (-3790 1635);
FORCEPROP 0 LASTPIN (-3800 4225) $PN CB60
J 0
(-3790 4235);
DISPLAY 0.489362 (-3790 4235);
PAINT MONO (-3790 4235);
FORCEPROP 0 LASTPIN (-3800 4175) $PN CC59
J 0
(-3790 4185);
DISPLAY 0.489362 (-3790 4185);
PAINT MONO (-3790 4185);
FORCEPROP 0 LASTPIN (-3800 4125) $PN CC60
J 0
(-3790 4135);
DISPLAY 0.489362 (-3790 4135);
PAINT MONO (-3790 4135);
FORCEPROP 0 LASTPIN (-3800 4075) $PN CD58
J 0
(-3790 4085);
DISPLAY 0.489362 (-3790 4085);
PAINT MONO (-3790 4085);
FORCEPROP 0 LASTPIN (-3800 4025) $PN CF60
J 0
(-3790 4035);
DISPLAY 0.489362 (-3790 4035);
PAINT MONO (-3790 4035);
FORCEPROP 0 LASTPIN (-3800 3975) $PN CG59
J 0
(-3790 3985);
DISPLAY 0.489362 (-3790 3985);
PAINT MONO (-3790 3985);
FORCEPROP 0 LASTPIN (-3800 3925) $PN CG60
J 0
(-3790 3935);
DISPLAY 0.489362 (-3790 3935);
PAINT MONO (-3790 3935);
FORCEPROP 0 LASTPIN (-3800 3875) $PN CH58
J 0
(-3790 3885);
DISPLAY 0.489362 (-3790 3885);
PAINT MONO (-3790 3885);
FORCEPROP 0 LASTPIN (-3800 3775) $PN CH60
J 0
(-3790 3785);
DISPLAY 0.489362 (-3790 3785);
PAINT MONO (-3790 3785);
FORCEPROP 0 LASTPIN (-3800 3725) $PN CJ59
J 0
(-3790 3735);
DISPLAY 0.489362 (-3790 3735);
PAINT MONO (-3790 3735);
FORCEPROP 0 LASTPIN (-3800 3675) $PN CJ60
J 0
(-3790 3685);
DISPLAY 0.489362 (-3790 3685);
PAINT MONO (-3790 3685);
FORCEPROP 0 LASTPIN (-3800 3625) $PN CK58
J 0
(-3790 3635);
DISPLAY 0.489362 (-3790 3635);
PAINT MONO (-3790 3635);
FORCEPROP 0 LASTPIN (-3800 3575) $PN CM60
J 0
(-3790 3585);
DISPLAY 0.489362 (-3790 3585);
PAINT MONO (-3790 3585);
FORCEPROP 0 LASTPIN (-3800 3525) $PN CN59
J 0
(-3790 3535);
DISPLAY 0.489362 (-3790 3535);
PAINT MONO (-3790 3535);
FORCEPROP 0 LASTPIN (-3800 3475) $PN CN60
J 0
(-3790 3485);
DISPLAY 0.489362 (-3790 3485);
PAINT MONO (-3790 3485);
FORCEPROP 0 LASTPIN (-3800 3425) $PN CP58
J 0
(-3790 3435);
DISPLAY 0.489362 (-3790 3435);
PAINT MONO (-3790 3435);
FORCEPROP 0 LASTPIN (-3800 3325) $PN CP60
J 0
(-3790 3335);
DISPLAY 0.489362 (-3790 3335);
PAINT MONO (-3790 3335);
FORCEPROP 0 LASTPIN (-3800 3275) $PN CR59
J 0
(-3790 3285);
DISPLAY 0.489362 (-3790 3285);
PAINT MONO (-3790 3285);
FORCEPROP 0 LASTPIN (-3800 3225) $PN CR60
J 0
(-3790 3235);
DISPLAY 0.489362 (-3790 3235);
PAINT MONO (-3790 3235);
FORCEPROP 0 LASTPIN (-3800 3175) $PN CT58
J 0
(-3790 3185);
DISPLAY 0.489362 (-3790 3185);
PAINT MONO (-3790 3185);
FORCEPROP 0 LASTPIN (-3800 3125) $PN CV60
J 0
(-3790 3135);
DISPLAY 0.489362 (-3790 3135);
PAINT MONO (-3790 3135);
FORCEPROP 0 LASTPIN (-3800 3075) $PN CW59
J 0
(-3790 3085);
DISPLAY 0.489362 (-3790 3085);
PAINT MONO (-3790 3085);
FORCEPROP 0 LASTPIN (-3800 3025) $PN CW60
J 0
(-3790 3035);
DISPLAY 0.489362 (-3790 3035);
PAINT MONO (-3790 3035);
FORCEPROP 0 LASTPIN (-3800 2975) $PN CY58
J 0
(-3790 2985);
DISPLAY 0.489362 (-3790 2985);
PAINT MONO (-3790 2985);
FORCEPROP 0 LASTPIN (-3800 2875) $PN CY60
J 0
(-3790 2885);
DISPLAY 0.489362 (-3790 2885);
PAINT MONO (-3790 2885);
FORCEPROP 0 LASTPIN (-3800 2825) $PN DA59
J 0
(-3790 2835);
DISPLAY 0.489362 (-3790 2835);
PAINT MONO (-3790 2835);
FORCEPROP 0 LASTPIN (-3800 2775) $PN DA60
J 0
(-3790 2785);
DISPLAY 0.489362 (-3790 2785);
PAINT MONO (-3790 2785);
FORCEPROP 0 LASTPIN (-3800 2725) $PN DB58
J 0
(-3790 2735);
DISPLAY 0.489362 (-3790 2735);
PAINT MONO (-3790 2735);
FORCEPROP 0 LASTPIN (-3800 2675) $PN DD60
J 0
(-3790 2685);
DISPLAY 0.489362 (-3790 2685);
PAINT MONO (-3790 2685);
FORCEPROP 0 LASTPIN (-3800 2625) $PN DE59
J 0
(-3790 2635);
DISPLAY 0.489362 (-3790 2635);
PAINT MONO (-3790 2635);
FORCEPROP 0 LASTPIN (-3800 2575) $PN DE60
J 0
(-3790 2585);
DISPLAY 0.489362 (-3790 2585);
PAINT MONO (-3790 2585);
FORCEPROP 0 LASTPIN (-3800 2525) $PN DF60
J 0
(-3790 2535);
DISPLAY 0.489362 (-3790 2535);
PAINT MONO (-3790 2535);
FORCEPROP 0 LASTPIN (-5400 4975) $PN CD60
J 2
(-5410 4985);
DISPLAY 0.489362 (-5410 4985);
PAINT MONO (-5410 4985);
FORCEPROP 0 LASTPIN (-5400 4875) $PN CK60
J 2
(-5410 4885);
DISPLAY 0.489362 (-5410 4885);
PAINT MONO (-5410 4885);
FORCEPROP 0 LASTPIN (-5400 4775) $PN CT60
J 2
(-5410 4785);
DISPLAY 0.489362 (-5410 4785);
PAINT MONO (-5410 4785);
FORCEPROP 0 LASTPIN (-5400 4675) $PN DB60
J 2
(-5410 4685);
DISPLAY 0.489362 (-5410 4685);
PAINT MONO (-5410 4685);
FORCEPROP 0 LASTPIN (-5400 4575) $PN BY58
J 2
(-5410 4585);
DISPLAY 0.489362 (-5410 4585);
PAINT MONO (-5410 4585);
FORCEPROP 0 LASTPIN (-5400 4475) $PN CF58
J 2
(-5410 4485);
DISPLAY 0.489362 (-5410 4485);
PAINT MONO (-5410 4485);
FORCEPROP 0 LASTPIN (-5400 4375) $PN CM58
J 2
(-5410 4385);
DISPLAY 0.489362 (-5410 4385);
PAINT MONO (-5410 4385);
FORCEPROP 0 LASTPIN (-5400 4275) $PN CV58
J 2
(-5410 4285);
DISPLAY 0.489362 (-5410 4285);
PAINT MONO (-5410 4285);
FORCEPROP 0 LASTPIN (-5400 4175) $PN DD58
J 2
(-5410 4185);
DISPLAY 0.489362 (-5410 4185);
PAINT MONO (-5410 4185);
FORCEPROP 0 LASTPIN (-5400 4075) $PN BV60
J 2
(-5410 4085);
DISPLAY 0.489362 (-5410 4085);
PAINT MONO (-5410 4085);
FORCEPROP 0 LASTPIN (-5400 4925) $PN CE60
J 2
(-5410 4935);
DISPLAY 0.489362 (-5410 4935);
PAINT MONO (-5410 4935);
FORCEPROP 0 LASTPIN (-5400 4825) $PN CL60
J 2
(-5410 4835);
DISPLAY 0.489362 (-5410 4835);
PAINT MONO (-5410 4835);
FORCEPROP 0 LASTPIN (-5400 4725) $PN CU60
J 2
(-5410 4735);
DISPLAY 0.489362 (-5410 4735);
PAINT MONO (-5410 4735);
FORCEPROP 0 LASTPIN (-5400 4625) $PN DC60
J 2
(-5410 4635);
DISPLAY 0.489362 (-5410 4635);
PAINT MONO (-5410 4635);
FORCEPROP 0 LASTPIN (-5400 4525) $PN BW59
J 2
(-5410 4535);
DISPLAY 0.489362 (-5410 4535);
PAINT MONO (-5410 4535);
FORCEPROP 0 LASTPIN (-5400 4425) $PN CE59
J 2
(-5410 4435);
DISPLAY 0.489362 (-5410 4435);
PAINT MONO (-5410 4435);
FORCEPROP 0 LASTPIN (-5400 4325) $PN CL59
J 2
(-5410 4335);
DISPLAY 0.489362 (-5410 4335);
PAINT MONO (-5410 4335);
FORCEPROP 0 LASTPIN (-5400 4225) $PN CU59
J 2
(-5410 4235);
DISPLAY 0.489362 (-5410 4235);
PAINT MONO (-5410 4235);
FORCEPROP 0 LASTPIN (-5400 4125) $PN DC59
J 2
(-5410 4135);
DISPLAY 0.489362 (-5410 4135);
PAINT MONO (-5410 4135);
FORCEPROP 0 LASTPIN (-5400 4025) $PN BW60
J 2
(-5410 4035);
DISPLAY 0.489362 (-5410 4035);
PAINT MONO (-5410 4035);
FORCEPROP 0 LASTPIN (-5400 2275) $PN BL60
J 2
(-5410 2285);
DISPLAY 0.489362 (-5410 2285);
PAINT MONO (-5410 2285);
FORCEPROP 0 LASTPIN (-5400 1225) $PN BF58
J 2
(-5410 1235);
DISPLAY 0.489362 (-5410 1235);
PAINT MONO (-5410 1235);
FORCEPROP 2 LAST PART_TYPE SMLF
J 0
(-5250 6405);
DISPLAY 1.021277 (-5250 6405);
FORCEPROP 1 LAST MATERIAL IO
J 0
(-5245 6207);
DISPLAY 0.489362 (-5245 6207);
PAINT SKYBLUE (-5245 6207);
FORCEPROP 2 LAST VALUE SOCKET6096_13568-001
J 0
(-5250 6305);
DISPLAY 0.489362 (-5250 6305);
PAINT SKYBLUE (-5250 6305);
FORCEPROP 1 LAST PART_NUMBER DGA^6000030
J 0
(-5245 6334);
DISPLAY 0.489362 (-5245 6334);
PAINT SKYBLUE (-5245 6334);
FORCEPROP 2 LAST CDS_LIB pure_quanta
J 0
(-4600 3650);
DISPLAY INVISIBLE (-4600 3650);
FORCEPROP 1 LAST CDS_LMAN_SYM_OUTLINE -650,2525,650,-2525
J 0
(-4600 3650);
DISPLAY 0.468085 (-4600 3650);
PAINT GREEN (-4600 3650);
DISPLAY INVISIBLE (-4600 3650);
FORCEPROP 1 LAST NEEDS_NO_SIZE TRUE
J 0
(-4600 3650);
DISPLAY 0.723404 (-4600 3650);
PAINT GREEN (-4600 3650);
DISPLAY INVISIBLE (-4600 3650);
FORCEPROP 1 LAST PATH I159
J 0
(-4600 3650);
DISPLAY 0.723404 (-4600 3650);
PAINT GREEN (-4600 3650);
DISPLAY INVISIBLE (-4600 3650);
FORCEADD OFFPAGE..3
(-2600 6050);
FORCEPROP 2 LAST $XR0 88 
J 0
(-2386 6050);
DISPLAY 0.638298 (-2386 6050);
PAINT MONO (-2386 6050);
FORCEPROP 2 LAST PATH I160
J 0
(-2375 6100);
DISPLAY 1.021277 (-2375 6100);
DISPLAY INVISIBLE (-2375 6100);
FORCEPROP 1 LAST COMMENT_BODY TRUE
J 0
(-2650 5950);
DISPLAY 0.872340 (-2650 5950);
PAINT GREEN (-2650 5950);
DISPLAY INVISIBLE (-2650 5950);
FORCEPROP 1 LAST OFFPAGE TRUE
J 0
(-2275 5925);
DISPLAY 0.872340 (-2275 5925);
PAINT GREEN (-2275 5925);
DISPLAY INVISIBLE (-2275 5925);
FORCEPROP 2 LAST CDS_LIB mstr_standard
J 0
(-2600 6050);
DISPLAY 0.723404 (-2600 6050);
PAINT MONO (-2600 6050);
DISPLAY INVISIBLE (-2600 6050);
FORCEADD OFFPAGE..3
(-2600 4250);
FORCEPROP 2 LAST $XR0 88 
J 0
(-2386 4250);
DISPLAY 0.638298 (-2386 4250);
PAINT MONO (-2386 4250);
FORCEPROP 2 LAST PATH I161
J 0
(-2375 4300);
DISPLAY 1.021277 (-2375 4300);
DISPLAY INVISIBLE (-2375 4300);
FORCEPROP 1 LAST COMMENT_BODY TRUE
J 0
(-2650 4150);
DISPLAY 0.872340 (-2650 4150);
PAINT GREEN (-2650 4150);
DISPLAY INVISIBLE (-2650 4150);
FORCEPROP 1 LAST OFFPAGE TRUE
J 0
(-2275 4125);
DISPLAY 0.872340 (-2275 4125);
PAINT GREEN (-2275 4125);
DISPLAY INVISIBLE (-2275 4125);
FORCEPROP 2 LAST CDS_LIB mstr_standard
J 0
(-2600 4250);
DISPLAY 0.723404 (-2600 4250);
PAINT MONO (-2600 4250);
DISPLAY INVISIBLE (-2600 4250);
FORCEADD TAP..1
(-3325 5925);
FORCEPROP 3 LASTPIN (-3375 5925) SIG_NAME M_D_CPU0_SA_DQ<2>
J 0
(-3365 5935);
DISPLAY 0.659574 (-3365 5935);
PAINT MONO (-3365 5935);
DISPLAY INVISIBLE (-3365 5935);
FORCEPROP 1 LASTPIN (-3375 5925) BN 2
J 0
(-3387 5933);
DISPLAY 0.489362 (-3387 5933);
PAINT GREEN (-3387 5933);
FORCEPROP 2 LAST CDS_LIB mstr_standard
J 0
(-3325 5925);
DISPLAY 0.723404 (-3325 5925);
PAINT MONO (-3325 5925);
DISPLAY INVISIBLE (-3325 5925);
FORCEPROP 1 LAST BODY_TYPE PLUMBING
J 0
(-3325 5975);
DISPLAY 0.872340 (-3325 5975);
PAINT GREEN (-3325 5975);
DISPLAY INVISIBLE (-3325 5975);
FORCEPROP 1 LAST HDL_TAP TRUE
J 0
(-3000 5800);
DISPLAY 0.872340 (-3000 5800);
DISPLAY INVISIBLE (-3000 5800);
FORCEPROP 1 LAST PATH I162
J 0
(-3327 5925);
DISPLAY 0.872340 (-3327 5925);
PAINT GREEN (-3327 5925);
DISPLAY INVISIBLE (-3327 5925);
FORCEADD TAP..1
(-3325 6025);
FORCEPROP 3 LASTPIN (-3375 6025) SIG_NAME M_D_CPU0_SA_DQ<0>
J 0
(-3365 6035);
DISPLAY 0.659574 (-3365 6035);
PAINT MONO (-3365 6035);
DISPLAY INVISIBLE (-3365 6035);
FORCEPROP 1 LASTPIN (-3375 6025) BN 0
J 0
(-3387 6033);
DISPLAY 0.489362 (-3387 6033);
PAINT GREEN (-3387 6033);
FORCEPROP 2 LAST CDS_LIB mstr_standard
J 0
(-3325 6025);
DISPLAY 0.723404 (-3325 6025);
PAINT MONO (-3325 6025);
DISPLAY INVISIBLE (-3325 6025);
FORCEPROP 1 LAST BODY_TYPE PLUMBING
J 0
(-3325 6075);
DISPLAY 0.872340 (-3325 6075);
PAINT GREEN (-3325 6075);
DISPLAY INVISIBLE (-3325 6075);
FORCEPROP 1 LAST HDL_TAP TRUE
J 0
(-3000 5900);
DISPLAY 0.872340 (-3000 5900);
DISPLAY INVISIBLE (-3000 5900);
FORCEPROP 1 LAST PATH I163
J 0
(-3327 6025);
DISPLAY 0.872340 (-3327 6025);
PAINT GREEN (-3327 6025);
DISPLAY INVISIBLE (-3327 6025);
FORCEADD TAP..1
(-3325 5975);
FORCEPROP 3 LASTPIN (-3375 5975) SIG_NAME M_D_CPU0_SA_DQ<1>
J 0
(-3365 5985);
DISPLAY 0.659574 (-3365 5985);
PAINT MONO (-3365 5985);
DISPLAY INVISIBLE (-3365 5985);
FORCEPROP 1 LASTPIN (-3375 5975) BN 1
J 0
(-3387 5983);
DISPLAY 0.489362 (-3387 5983);
PAINT GREEN (-3387 5983);
FORCEPROP 2 LAST CDS_LIB mstr_standard
J 0
(-3325 5975);
DISPLAY 0.723404 (-3325 5975);
PAINT MONO (-3325 5975);
DISPLAY INVISIBLE (-3325 5975);
FORCEPROP 1 LAST BODY_TYPE PLUMBING
J 0
(-3325 6025);
DISPLAY 0.872340 (-3325 6025);
PAINT GREEN (-3325 6025);
DISPLAY INVISIBLE (-3325 6025);
FORCEPROP 1 LAST HDL_TAP TRUE
J 0
(-3000 5850);
DISPLAY 0.872340 (-3000 5850);
DISPLAY INVISIBLE (-3000 5850);
FORCEPROP 1 LAST PATH I164
J 0
(-3327 5975);
DISPLAY 0.872340 (-3327 5975);
PAINT GREEN (-3327 5975);
DISPLAY INVISIBLE (-3327 5975);
FORCEADD TAP..1
(-3325 5775);
FORCEPROP 3 LASTPIN (-3375 5775) SIG_NAME M_D_CPU0_SA_DQ<5>
J 0
(-3365 5785);
DISPLAY 0.659574 (-3365 5785);
PAINT MONO (-3365 5785);
DISPLAY INVISIBLE (-3365 5785);
FORCEPROP 1 LASTPIN (-3375 5775) BN 5
J 0
(-3387 5783);
DISPLAY 0.489362 (-3387 5783);
PAINT GREEN (-3387 5783);
FORCEPROP 2 LAST CDS_LIB mstr_standard
J 0
(-3325 5775);
DISPLAY 0.723404 (-3325 5775);
PAINT MONO (-3325 5775);
DISPLAY INVISIBLE (-3325 5775);
FORCEPROP 1 LAST BODY_TYPE PLUMBING
J 0
(-3325 5825);
DISPLAY 0.872340 (-3325 5825);
PAINT GREEN (-3325 5825);
DISPLAY INVISIBLE (-3325 5825);
FORCEPROP 1 LAST HDL_TAP TRUE
J 0
(-3000 5650);
DISPLAY 0.872340 (-3000 5650);
DISPLAY INVISIBLE (-3000 5650);
FORCEPROP 1 LAST PATH I165
J 0
(-3327 5775);
DISPLAY 0.872340 (-3327 5775);
PAINT GREEN (-3327 5775);
DISPLAY INVISIBLE (-3327 5775);
FORCEADD TAP..1
(-3325 5875);
FORCEPROP 3 LASTPIN (-3375 5875) SIG_NAME M_D_CPU0_SA_DQ<3>
J 0
(-3365 5885);
DISPLAY 0.659574 (-3365 5885);
PAINT MONO (-3365 5885);
DISPLAY INVISIBLE (-3365 5885);
FORCEPROP 1 LASTPIN (-3375 5875) BN 3
J 0
(-3387 5883);
DISPLAY 0.489362 (-3387 5883);
PAINT GREEN (-3387 5883);
FORCEPROP 2 LAST CDS_LIB mstr_standard
J 0
(-3325 5875);
DISPLAY 0.723404 (-3325 5875);
PAINT MONO (-3325 5875);
DISPLAY INVISIBLE (-3325 5875);
FORCEPROP 1 LAST BODY_TYPE PLUMBING
J 0
(-3325 5925);
DISPLAY 0.872340 (-3325 5925);
PAINT GREEN (-3325 5925);
DISPLAY INVISIBLE (-3325 5925);
FORCEPROP 1 LAST HDL_TAP TRUE
J 0
(-3000 5750);
DISPLAY 0.872340 (-3000 5750);
DISPLAY INVISIBLE (-3000 5750);
FORCEPROP 1 LAST PATH I166
J 0
(-3327 5875);
DISPLAY 0.872340 (-3327 5875);
PAINT GREEN (-3327 5875);
DISPLAY INVISIBLE (-3327 5875);
FORCEADD TAP..1
(-3325 5825);
FORCEPROP 3 LASTPIN (-3375 5825) SIG_NAME M_D_CPU0_SA_DQ<4>
J 0
(-3365 5835);
DISPLAY 0.659574 (-3365 5835);
PAINT MONO (-3365 5835);
DISPLAY INVISIBLE (-3365 5835);
FORCEPROP 1 LASTPIN (-3375 5825) BN 4
J 0
(-3387 5833);
DISPLAY 0.489362 (-3387 5833);
PAINT GREEN (-3387 5833);
FORCEPROP 2 LAST CDS_LIB mstr_standard
J 0
(-3325 5825);
DISPLAY 0.723404 (-3325 5825);
PAINT MONO (-3325 5825);
DISPLAY INVISIBLE (-3325 5825);
FORCEPROP 1 LAST BODY_TYPE PLUMBING
J 0
(-3325 5875);
DISPLAY 0.872340 (-3325 5875);
PAINT GREEN (-3325 5875);
DISPLAY INVISIBLE (-3325 5875);
FORCEPROP 1 LAST HDL_TAP TRUE
J 0
(-3000 5700);
DISPLAY 0.872340 (-3000 5700);
DISPLAY INVISIBLE (-3000 5700);
FORCEPROP 1 LAST PATH I167
J 0
(-3327 5825);
DISPLAY 0.872340 (-3327 5825);
PAINT GREEN (-3327 5825);
DISPLAY INVISIBLE (-3327 5825);
FORCEADD TAP..1
(-3325 5725);
FORCEPROP 3 LASTPIN (-3375 5725) SIG_NAME M_D_CPU0_SA_DQ<6>
J 0
(-3365 5735);
DISPLAY 0.659574 (-3365 5735);
PAINT MONO (-3365 5735);
DISPLAY INVISIBLE (-3365 5735);
FORCEPROP 1 LASTPIN (-3375 5725) BN 6
J 0
(-3387 5733);
DISPLAY 0.489362 (-3387 5733);
PAINT GREEN (-3387 5733);
FORCEPROP 2 LAST CDS_LIB mstr_standard
J 0
(-3325 5725);
DISPLAY 0.723404 (-3325 5725);
PAINT MONO (-3325 5725);
DISPLAY INVISIBLE (-3325 5725);
FORCEPROP 1 LAST BODY_TYPE PLUMBING
J 0
(-3325 5775);
DISPLAY 0.872340 (-3325 5775);
PAINT GREEN (-3325 5775);
DISPLAY INVISIBLE (-3325 5775);
FORCEPROP 1 LAST HDL_TAP TRUE
J 0
(-3000 5600);
DISPLAY 0.872340 (-3000 5600);
DISPLAY INVISIBLE (-3000 5600);
FORCEPROP 1 LAST PATH I168
J 0
(-3327 5725);
DISPLAY 0.872340 (-3327 5725);
PAINT GREEN (-3327 5725);
DISPLAY INVISIBLE (-3327 5725);
FORCEADD TAP..1
(-3325 5675);
FORCEPROP 3 LASTPIN (-3375 5675) SIG_NAME M_D_CPU0_SA_DQ<7>
J 0
(-3365 5685);
DISPLAY 0.659574 (-3365 5685);
PAINT MONO (-3365 5685);
DISPLAY INVISIBLE (-3365 5685);
FORCEPROP 1 LASTPIN (-3375 5675) BN 7
J 0
(-3387 5683);
DISPLAY 0.489362 (-3387 5683);
PAINT GREEN (-3387 5683);
FORCEPROP 2 LAST CDS_LIB mstr_standard
J 0
(-3325 5675);
DISPLAY 0.723404 (-3325 5675);
PAINT MONO (-3325 5675);
DISPLAY INVISIBLE (-3325 5675);
FORCEPROP 1 LAST BODY_TYPE PLUMBING
J 0
(-3325 5725);
DISPLAY 0.872340 (-3325 5725);
PAINT GREEN (-3325 5725);
DISPLAY INVISIBLE (-3325 5725);
FORCEPROP 1 LAST HDL_TAP TRUE
J 0
(-3000 5550);
DISPLAY 0.872340 (-3000 5550);
DISPLAY INVISIBLE (-3000 5550);
FORCEPROP 1 LAST PATH I169
J 0
(-3327 5675);
DISPLAY 0.872340 (-3327 5675);
PAINT GREEN (-3327 5675);
DISPLAY INVISIBLE (-3327 5675);
FORCEADD TAP..1
(-3325 5525);
FORCEPROP 3 LASTPIN (-3375 5525) SIG_NAME M_D_CPU0_SA_DQ<9>
J 0
(-3365 5535);
DISPLAY 0.659574 (-3365 5535);
PAINT MONO (-3365 5535);
DISPLAY INVISIBLE (-3365 5535);
FORCEPROP 1 LASTPIN (-3375 5525) BN 9
J 0
(-3387 5533);
DISPLAY 0.489362 (-3387 5533);
PAINT GREEN (-3387 5533);
FORCEPROP 2 LAST CDS_LIB mstr_standard
J 0
(-3325 5525);
DISPLAY 0.723404 (-3325 5525);
PAINT MONO (-3325 5525);
DISPLAY INVISIBLE (-3325 5525);
FORCEPROP 1 LAST BODY_TYPE PLUMBING
J 0
(-3325 5575);
DISPLAY 0.872340 (-3325 5575);
PAINT GREEN (-3325 5575);
DISPLAY INVISIBLE (-3325 5575);
FORCEPROP 1 LAST HDL_TAP TRUE
J 0
(-3000 5400);
DISPLAY 0.872340 (-3000 5400);
DISPLAY INVISIBLE (-3000 5400);
FORCEPROP 1 LAST PATH I170
J 0
(-3327 5525);
DISPLAY 0.872340 (-3327 5525);
PAINT GREEN (-3327 5525);
DISPLAY INVISIBLE (-3327 5525);
FORCEADD TAP..1
(-3325 5575);
FORCEPROP 3 LASTPIN (-3375 5575) SIG_NAME M_D_CPU0_SA_DQ<8>
J 0
(-3365 5585);
DISPLAY 0.659574 (-3365 5585);
PAINT MONO (-3365 5585);
DISPLAY INVISIBLE (-3365 5585);
FORCEPROP 1 LASTPIN (-3375 5575) BN 8
J 0
(-3387 5583);
DISPLAY 0.489362 (-3387 5583);
PAINT GREEN (-3387 5583);
FORCEPROP 2 LAST CDS_LIB mstr_standard
J 0
(-3325 5575);
DISPLAY 0.723404 (-3325 5575);
PAINT MONO (-3325 5575);
DISPLAY INVISIBLE (-3325 5575);
FORCEPROP 1 LAST BODY_TYPE PLUMBING
J 0
(-3325 5625);
DISPLAY 0.872340 (-3325 5625);
PAINT GREEN (-3325 5625);
DISPLAY INVISIBLE (-3325 5625);
FORCEPROP 1 LAST HDL_TAP TRUE
J 0
(-3000 5450);
DISPLAY 0.872340 (-3000 5450);
DISPLAY INVISIBLE (-3000 5450);
FORCEPROP 1 LAST PATH I171
J 0
(-3327 5575);
DISPLAY 0.872340 (-3327 5575);
PAINT GREEN (-3327 5575);
DISPLAY INVISIBLE (-3327 5575);
FORCEADD TAP..1
(-3325 5475);
FORCEPROP 3 LASTPIN (-3375 5475) SIG_NAME M_D_CPU0_SA_DQ<10>
J 0
(-3365 5485);
DISPLAY 0.659574 (-3365 5485);
PAINT MONO (-3365 5485);
DISPLAY INVISIBLE (-3365 5485);
FORCEPROP 1 LASTPIN (-3375 5475) BN 10
J 0
(-3387 5483);
DISPLAY 0.489362 (-3387 5483);
PAINT GREEN (-3387 5483);
FORCEPROP 2 LAST CDS_LIB mstr_standard
J 0
(-3325 5475);
DISPLAY 0.723404 (-3325 5475);
PAINT MONO (-3325 5475);
DISPLAY INVISIBLE (-3325 5475);
FORCEPROP 1 LAST BODY_TYPE PLUMBING
J 0
(-3325 5525);
DISPLAY 0.872340 (-3325 5525);
PAINT GREEN (-3325 5525);
DISPLAY INVISIBLE (-3325 5525);
FORCEPROP 1 LAST HDL_TAP TRUE
J 0
(-3000 5350);
DISPLAY 0.872340 (-3000 5350);
DISPLAY INVISIBLE (-3000 5350);
FORCEPROP 1 LAST PATH I172
J 0
(-3327 5475);
DISPLAY 0.872340 (-3327 5475);
PAINT GREEN (-3327 5475);
DISPLAY INVISIBLE (-3327 5475);
FORCEADD TAP..1
(-3325 5425);
FORCEPROP 3 LASTPIN (-3375 5425) SIG_NAME M_D_CPU0_SA_DQ<11>
J 0
(-3365 5435);
DISPLAY 0.659574 (-3365 5435);
PAINT MONO (-3365 5435);
DISPLAY INVISIBLE (-3365 5435);
FORCEPROP 1 LASTPIN (-3375 5425) BN 11
J 0
(-3387 5433);
DISPLAY 0.489362 (-3387 5433);
PAINT GREEN (-3387 5433);
FORCEPROP 2 LAST CDS_LIB mstr_standard
J 0
(-3325 5425);
DISPLAY 0.723404 (-3325 5425);
PAINT MONO (-3325 5425);
DISPLAY INVISIBLE (-3325 5425);
FORCEPROP 1 LAST BODY_TYPE PLUMBING
J 0
(-3325 5475);
DISPLAY 0.872340 (-3325 5475);
PAINT GREEN (-3325 5475);
DISPLAY INVISIBLE (-3325 5475);
FORCEPROP 1 LAST HDL_TAP TRUE
J 0
(-3000 5300);
DISPLAY 0.872340 (-3000 5300);
DISPLAY INVISIBLE (-3000 5300);
FORCEPROP 1 LAST PATH I173
J 0
(-3327 5425);
DISPLAY 0.872340 (-3327 5425);
PAINT GREEN (-3327 5425);
DISPLAY INVISIBLE (-3327 5425);
FORCEADD TAP..1
(-3325 5275);
FORCEPROP 3 LASTPIN (-3375 5275) SIG_NAME M_D_CPU0_SA_DQ<14>
J 0
(-3365 5285);
DISPLAY 0.659574 (-3365 5285);
PAINT MONO (-3365 5285);
DISPLAY INVISIBLE (-3365 5285);
FORCEPROP 1 LASTPIN (-3375 5275) BN 14
J 0
(-3387 5283);
DISPLAY 0.489362 (-3387 5283);
PAINT GREEN (-3387 5283);
FORCEPROP 2 LAST CDS_LIB mstr_standard
J 0
(-3325 5275);
DISPLAY 0.723404 (-3325 5275);
PAINT MONO (-3325 5275);
DISPLAY INVISIBLE (-3325 5275);
FORCEPROP 1 LAST BODY_TYPE PLUMBING
J 0
(-3325 5325);
DISPLAY 0.872340 (-3325 5325);
PAINT GREEN (-3325 5325);
DISPLAY INVISIBLE (-3325 5325);
FORCEPROP 1 LAST HDL_TAP TRUE
J 0
(-3000 5150);
DISPLAY 0.872340 (-3000 5150);
DISPLAY INVISIBLE (-3000 5150);
FORCEPROP 1 LAST PATH I174
J 0
(-3327 5275);
DISPLAY 0.872340 (-3327 5275);
PAINT GREEN (-3327 5275);
DISPLAY INVISIBLE (-3327 5275);
FORCEADD TAP..1
(-3325 5375);
FORCEPROP 3 LASTPIN (-3375 5375) SIG_NAME M_D_CPU0_SA_DQ<12>
J 0
(-3365 5385);
DISPLAY 0.659574 (-3365 5385);
PAINT MONO (-3365 5385);
DISPLAY INVISIBLE (-3365 5385);
FORCEPROP 1 LASTPIN (-3375 5375) BN 12
J 0
(-3387 5383);
DISPLAY 0.489362 (-3387 5383);
PAINT GREEN (-3387 5383);
FORCEPROP 2 LAST CDS_LIB mstr_standard
J 0
(-3325 5375);
DISPLAY 0.723404 (-3325 5375);
PAINT MONO (-3325 5375);
DISPLAY INVISIBLE (-3325 5375);
FORCEPROP 1 LAST BODY_TYPE PLUMBING
J 0
(-3325 5425);
DISPLAY 0.872340 (-3325 5425);
PAINT GREEN (-3325 5425);
DISPLAY INVISIBLE (-3325 5425);
FORCEPROP 1 LAST HDL_TAP TRUE
J 0
(-3000 5250);
DISPLAY 0.872340 (-3000 5250);
DISPLAY INVISIBLE (-3000 5250);
FORCEPROP 1 LAST PATH I175
J 0
(-3327 5375);
DISPLAY 0.872340 (-3327 5375);
PAINT GREEN (-3327 5375);
DISPLAY INVISIBLE (-3327 5375);
FORCEADD TAP..1
(-3325 5325);
FORCEPROP 3 LASTPIN (-3375 5325) SIG_NAME M_D_CPU0_SA_DQ<13>
J 0
(-3365 5335);
DISPLAY 0.659574 (-3365 5335);
PAINT MONO (-3365 5335);
DISPLAY INVISIBLE (-3365 5335);
FORCEPROP 1 LASTPIN (-3375 5325) BN 13
J 0
(-3387 5333);
DISPLAY 0.489362 (-3387 5333);
PAINT GREEN (-3387 5333);
FORCEPROP 2 LAST CDS_LIB mstr_standard
J 0
(-3325 5325);
DISPLAY 0.723404 (-3325 5325);
PAINT MONO (-3325 5325);
DISPLAY INVISIBLE (-3325 5325);
FORCEPROP 1 LAST BODY_TYPE PLUMBING
J 0
(-3325 5375);
DISPLAY 0.872340 (-3325 5375);
PAINT GREEN (-3325 5375);
DISPLAY INVISIBLE (-3325 5375);
FORCEPROP 1 LAST HDL_TAP TRUE
J 0
(-3000 5200);
DISPLAY 0.872340 (-3000 5200);
DISPLAY INVISIBLE (-3000 5200);
FORCEPROP 1 LAST PATH I176
J 0
(-3327 5325);
DISPLAY 0.872340 (-3327 5325);
PAINT GREEN (-3327 5325);
DISPLAY INVISIBLE (-3327 5325);
FORCEADD TAP..1
(-3325 5225);
FORCEPROP 3 LASTPIN (-3375 5225) SIG_NAME M_D_CPU0_SA_DQ<15>
J 0
(-3365 5235);
DISPLAY 0.659574 (-3365 5235);
PAINT MONO (-3365 5235);
DISPLAY INVISIBLE (-3365 5235);
FORCEPROP 1 LASTPIN (-3375 5225) BN 15
J 0
(-3387 5233);
DISPLAY 0.489362 (-3387 5233);
PAINT GREEN (-3387 5233);
FORCEPROP 2 LAST CDS_LIB mstr_standard
J 0
(-3325 5225);
DISPLAY 0.723404 (-3325 5225);
PAINT MONO (-3325 5225);
DISPLAY INVISIBLE (-3325 5225);
FORCEPROP 1 LAST BODY_TYPE PLUMBING
J 0
(-3325 5275);
DISPLAY 0.872340 (-3325 5275);
PAINT GREEN (-3325 5275);
DISPLAY INVISIBLE (-3325 5275);
FORCEPROP 1 LAST HDL_TAP TRUE
J 0
(-3000 5100);
DISPLAY 0.872340 (-3000 5100);
DISPLAY INVISIBLE (-3000 5100);
FORCEPROP 1 LAST PATH I177
J 0
(-3327 5225);
DISPLAY 0.872340 (-3327 5225);
PAINT GREEN (-3327 5225);
DISPLAY INVISIBLE (-3327 5225);
FORCEADD TAP..1
(-3325 5125);
FORCEPROP 3 LASTPIN (-3375 5125) SIG_NAME M_D_CPU0_SA_DQ<16>
J 0
(-3365 5135);
DISPLAY 0.659574 (-3365 5135);
PAINT MONO (-3365 5135);
DISPLAY INVISIBLE (-3365 5135);
FORCEPROP 1 LASTPIN (-3375 5125) BN 16
J 0
(-3387 5133);
DISPLAY 0.489362 (-3387 5133);
PAINT GREEN (-3387 5133);
FORCEPROP 2 LAST CDS_LIB mstr_standard
J 0
(-3325 5125);
DISPLAY 0.723404 (-3325 5125);
PAINT MONO (-3325 5125);
DISPLAY INVISIBLE (-3325 5125);
FORCEPROP 1 LAST BODY_TYPE PLUMBING
J 0
(-3325 5175);
DISPLAY 0.872340 (-3325 5175);
PAINT GREEN (-3325 5175);
DISPLAY INVISIBLE (-3325 5175);
FORCEPROP 1 LAST HDL_TAP TRUE
J 0
(-3000 5000);
DISPLAY 0.872340 (-3000 5000);
DISPLAY INVISIBLE (-3000 5000);
FORCEPROP 1 LAST PATH I178
J 0
(-3327 5125);
DISPLAY 0.872340 (-3327 5125);
PAINT GREEN (-3327 5125);
DISPLAY INVISIBLE (-3327 5125);
FORCEADD TAP..1
(-3325 5025);
FORCEPROP 3 LASTPIN (-3375 5025) SIG_NAME M_D_CPU0_SA_DQ<18>
J 0
(-3365 5035);
DISPLAY 0.659574 (-3365 5035);
PAINT MONO (-3365 5035);
DISPLAY INVISIBLE (-3365 5035);
FORCEPROP 1 LASTPIN (-3375 5025) BN 18
J 0
(-3387 5033);
DISPLAY 0.489362 (-3387 5033);
PAINT GREEN (-3387 5033);
FORCEPROP 2 LAST CDS_LIB mstr_standard
J 0
(-3325 5025);
DISPLAY 0.723404 (-3325 5025);
PAINT MONO (-3325 5025);
DISPLAY INVISIBLE (-3325 5025);
FORCEPROP 1 LAST BODY_TYPE PLUMBING
J 0
(-3325 5075);
DISPLAY 0.872340 (-3325 5075);
PAINT GREEN (-3325 5075);
DISPLAY INVISIBLE (-3325 5075);
FORCEPROP 1 LAST HDL_TAP TRUE
J 0
(-3000 4900);
DISPLAY 0.872340 (-3000 4900);
DISPLAY INVISIBLE (-3000 4900);
FORCEPROP 1 LAST PATH I179
J 0
(-3327 5025);
DISPLAY 0.872340 (-3327 5025);
PAINT GREEN (-3327 5025);
DISPLAY INVISIBLE (-3327 5025);
FORCEADD TAP..1
(-3325 5075);
FORCEPROP 3 LASTPIN (-3375 5075) SIG_NAME M_D_CPU0_SA_DQ<17>
J 0
(-3365 5085);
DISPLAY 0.659574 (-3365 5085);
PAINT MONO (-3365 5085);
DISPLAY INVISIBLE (-3365 5085);
FORCEPROP 1 LASTPIN (-3375 5075) BN 17
J 0
(-3387 5083);
DISPLAY 0.489362 (-3387 5083);
PAINT GREEN (-3387 5083);
FORCEPROP 2 LAST CDS_LIB mstr_standard
J 0
(-3325 5075);
DISPLAY 0.723404 (-3325 5075);
PAINT MONO (-3325 5075);
DISPLAY INVISIBLE (-3325 5075);
FORCEPROP 1 LAST BODY_TYPE PLUMBING
J 0
(-3325 5125);
DISPLAY 0.872340 (-3325 5125);
PAINT GREEN (-3325 5125);
DISPLAY INVISIBLE (-3325 5125);
FORCEPROP 1 LAST HDL_TAP TRUE
J 0
(-3000 4950);
DISPLAY 0.872340 (-3000 4950);
DISPLAY INVISIBLE (-3000 4950);
FORCEPROP 1 LAST PATH I180
J 0
(-3327 5075);
DISPLAY 0.872340 (-3327 5075);
PAINT GREEN (-3327 5075);
DISPLAY INVISIBLE (-3327 5075);
FORCEADD TAP..1
(-3325 4975);
FORCEPROP 3 LASTPIN (-3375 4975) SIG_NAME M_D_CPU0_SA_DQ<19>
J 0
(-3365 4985);
DISPLAY 0.659574 (-3365 4985);
PAINT MONO (-3365 4985);
DISPLAY INVISIBLE (-3365 4985);
FORCEPROP 1 LASTPIN (-3375 4975) BN 19
J 0
(-3387 4983);
DISPLAY 0.489362 (-3387 4983);
PAINT GREEN (-3387 4983);
FORCEPROP 2 LAST CDS_LIB mstr_standard
J 0
(-3325 4975);
DISPLAY 0.723404 (-3325 4975);
PAINT MONO (-3325 4975);
DISPLAY INVISIBLE (-3325 4975);
FORCEPROP 1 LAST BODY_TYPE PLUMBING
J 0
(-3325 5025);
DISPLAY 0.872340 (-3325 5025);
PAINT GREEN (-3325 5025);
DISPLAY INVISIBLE (-3325 5025);
FORCEPROP 1 LAST HDL_TAP TRUE
J 0
(-3000 4850);
DISPLAY 0.872340 (-3000 4850);
DISPLAY INVISIBLE (-3000 4850);
FORCEPROP 1 LAST PATH I181
J 0
(-3327 4975);
DISPLAY 0.872340 (-3327 4975);
PAINT GREEN (-3327 4975);
DISPLAY INVISIBLE (-3327 4975);
FORCEADD TAP..1
(-3325 4875);
FORCEPROP 3 LASTPIN (-3375 4875) SIG_NAME M_D_CPU0_SA_DQ<21>
J 0
(-3365 4885);
DISPLAY 0.659574 (-3365 4885);
PAINT MONO (-3365 4885);
DISPLAY INVISIBLE (-3365 4885);
FORCEPROP 1 LASTPIN (-3375 4875) BN 21
J 0
(-3387 4883);
DISPLAY 0.489362 (-3387 4883);
PAINT GREEN (-3387 4883);
FORCEPROP 2 LAST CDS_LIB mstr_standard
J 0
(-3325 4875);
DISPLAY 0.723404 (-3325 4875);
PAINT MONO (-3325 4875);
DISPLAY INVISIBLE (-3325 4875);
FORCEPROP 1 LAST BODY_TYPE PLUMBING
J 0
(-3325 4925);
DISPLAY 0.872340 (-3325 4925);
PAINT GREEN (-3325 4925);
DISPLAY INVISIBLE (-3325 4925);
FORCEPROP 1 LAST HDL_TAP TRUE
J 0
(-3000 4750);
DISPLAY 0.872340 (-3000 4750);
DISPLAY INVISIBLE (-3000 4750);
FORCEPROP 1 LAST PATH I182
J 0
(-3327 4875);
DISPLAY 0.872340 (-3327 4875);
PAINT GREEN (-3327 4875);
DISPLAY INVISIBLE (-3327 4875);
FORCEADD TAP..1
(-3325 4925);
FORCEPROP 3 LASTPIN (-3375 4925) SIG_NAME M_D_CPU0_SA_DQ<20>
J 0
(-3365 4935);
DISPLAY 0.659574 (-3365 4935);
PAINT MONO (-3365 4935);
DISPLAY INVISIBLE (-3365 4935);
FORCEPROP 1 LASTPIN (-3375 4925) BN 20
J 0
(-3387 4933);
DISPLAY 0.489362 (-3387 4933);
PAINT GREEN (-3387 4933);
FORCEPROP 2 LAST CDS_LIB mstr_standard
J 0
(-3325 4925);
DISPLAY 0.723404 (-3325 4925);
PAINT MONO (-3325 4925);
DISPLAY INVISIBLE (-3325 4925);
FORCEPROP 1 LAST BODY_TYPE PLUMBING
J 0
(-3325 4975);
DISPLAY 0.872340 (-3325 4975);
PAINT GREEN (-3325 4975);
DISPLAY INVISIBLE (-3325 4975);
FORCEPROP 1 LAST HDL_TAP TRUE
J 0
(-3000 4800);
DISPLAY 0.872340 (-3000 4800);
DISPLAY INVISIBLE (-3000 4800);
FORCEPROP 1 LAST PATH I183
J 0
(-3327 4925);
DISPLAY 0.872340 (-3327 4925);
PAINT GREEN (-3327 4925);
DISPLAY INVISIBLE (-3327 4925);
FORCEADD TAP..1
(-3325 4675);
FORCEPROP 3 LASTPIN (-3375 4675) SIG_NAME M_D_CPU0_SA_DQ<24>
J 0
(-3365 4685);
DISPLAY 0.659574 (-3365 4685);
PAINT MONO (-3365 4685);
DISPLAY INVISIBLE (-3365 4685);
FORCEPROP 1 LASTPIN (-3375 4675) BN 24
J 0
(-3387 4683);
DISPLAY 0.489362 (-3387 4683);
PAINT GREEN (-3387 4683);
FORCEPROP 2 LAST CDS_LIB mstr_standard
J 0
(-3325 4675);
DISPLAY 0.723404 (-3325 4675);
PAINT MONO (-3325 4675);
DISPLAY INVISIBLE (-3325 4675);
FORCEPROP 1 LAST BODY_TYPE PLUMBING
J 0
(-3325 4725);
DISPLAY 0.872340 (-3325 4725);
PAINT GREEN (-3325 4725);
DISPLAY INVISIBLE (-3325 4725);
FORCEPROP 1 LAST HDL_TAP TRUE
J 0
(-3000 4550);
DISPLAY 0.872340 (-3000 4550);
DISPLAY INVISIBLE (-3000 4550);
FORCEPROP 1 LAST PATH I184
J 0
(-3327 4675);
DISPLAY 0.872340 (-3327 4675);
PAINT GREEN (-3327 4675);
DISPLAY INVISIBLE (-3327 4675);
FORCEADD TAP..1
(-3325 4625);
FORCEPROP 3 LASTPIN (-3375 4625) SIG_NAME M_D_CPU0_SA_DQ<25>
J 0
(-3365 4635);
DISPLAY 0.659574 (-3365 4635);
PAINT MONO (-3365 4635);
DISPLAY INVISIBLE (-3365 4635);
FORCEPROP 1 LASTPIN (-3375 4625) BN 25
J 0
(-3387 4633);
DISPLAY 0.489362 (-3387 4633);
PAINT GREEN (-3387 4633);
FORCEPROP 2 LAST CDS_LIB mstr_standard
J 0
(-3325 4625);
DISPLAY 0.723404 (-3325 4625);
PAINT MONO (-3325 4625);
DISPLAY INVISIBLE (-3325 4625);
FORCEPROP 1 LAST BODY_TYPE PLUMBING
J 0
(-3325 4675);
DISPLAY 0.872340 (-3325 4675);
PAINT GREEN (-3325 4675);
DISPLAY INVISIBLE (-3325 4675);
FORCEPROP 1 LAST HDL_TAP TRUE
J 0
(-3000 4500);
DISPLAY 0.872340 (-3000 4500);
DISPLAY INVISIBLE (-3000 4500);
FORCEPROP 1 LAST PATH I185
J 0
(-3327 4625);
DISPLAY 0.872340 (-3327 4625);
PAINT GREEN (-3327 4625);
DISPLAY INVISIBLE (-3327 4625);
FORCEADD TAP..1
(-3325 4775);
FORCEPROP 3 LASTPIN (-3375 4775) SIG_NAME M_D_CPU0_SA_DQ<23>
J 0
(-3365 4785);
DISPLAY 0.659574 (-3365 4785);
PAINT MONO (-3365 4785);
DISPLAY INVISIBLE (-3365 4785);
FORCEPROP 1 LASTPIN (-3375 4775) BN 23
J 0
(-3387 4783);
DISPLAY 0.489362 (-3387 4783);
PAINT GREEN (-3387 4783);
FORCEPROP 2 LAST CDS_LIB mstr_standard
J 0
(-3325 4775);
DISPLAY 0.723404 (-3325 4775);
PAINT MONO (-3325 4775);
DISPLAY INVISIBLE (-3325 4775);
FORCEPROP 1 LAST BODY_TYPE PLUMBING
J 0
(-3325 4825);
DISPLAY 0.872340 (-3325 4825);
PAINT GREEN (-3325 4825);
DISPLAY INVISIBLE (-3325 4825);
FORCEPROP 1 LAST HDL_TAP TRUE
J 0
(-3000 4650);
DISPLAY 0.872340 (-3000 4650);
DISPLAY INVISIBLE (-3000 4650);
FORCEPROP 1 LAST PATH I186
J 0
(-3327 4775);
DISPLAY 0.872340 (-3327 4775);
PAINT GREEN (-3327 4775);
DISPLAY INVISIBLE (-3327 4775);
FORCEADD TAP..1
(-3325 4825);
FORCEPROP 3 LASTPIN (-3375 4825) SIG_NAME M_D_CPU0_SA_DQ<22>
J 0
(-3365 4835);
DISPLAY 0.659574 (-3365 4835);
PAINT MONO (-3365 4835);
DISPLAY INVISIBLE (-3365 4835);
FORCEPROP 1 LASTPIN (-3375 4825) BN 22
J 0
(-3387 4833);
DISPLAY 0.489362 (-3387 4833);
PAINT GREEN (-3387 4833);
FORCEPROP 2 LAST CDS_LIB mstr_standard
J 0
(-3325 4825);
DISPLAY 0.723404 (-3325 4825);
PAINT MONO (-3325 4825);
DISPLAY INVISIBLE (-3325 4825);
FORCEPROP 1 LAST BODY_TYPE PLUMBING
J 0
(-3325 4875);
DISPLAY 0.872340 (-3325 4875);
PAINT GREEN (-3325 4875);
DISPLAY INVISIBLE (-3325 4875);
FORCEPROP 1 LAST HDL_TAP TRUE
J 0
(-3000 4700);
DISPLAY 0.872340 (-3000 4700);
DISPLAY INVISIBLE (-3000 4700);
FORCEPROP 1 LAST PATH I187
J 0
(-3327 4825);
DISPLAY 0.872340 (-3327 4825);
PAINT GREEN (-3327 4825);
DISPLAY INVISIBLE (-3327 4825);
FORCEADD TAP..1
(-3325 4575);
FORCEPROP 3 LASTPIN (-3375 4575) SIG_NAME M_D_CPU0_SA_DQ<26>
J 0
(-3365 4585);
DISPLAY 0.659574 (-3365 4585);
PAINT MONO (-3365 4585);
DISPLAY INVISIBLE (-3365 4585);
FORCEPROP 1 LASTPIN (-3375 4575) BN 26
J 0
(-3387 4583);
DISPLAY 0.489362 (-3387 4583);
PAINT GREEN (-3387 4583);
FORCEPROP 2 LAST CDS_LIB mstr_standard
J 0
(-3325 4575);
DISPLAY 0.723404 (-3325 4575);
PAINT MONO (-3325 4575);
DISPLAY INVISIBLE (-3325 4575);
FORCEPROP 1 LAST BODY_TYPE PLUMBING
J 0
(-3325 4625);
DISPLAY 0.872340 (-3325 4625);
PAINT GREEN (-3325 4625);
DISPLAY INVISIBLE (-3325 4625);
FORCEPROP 1 LAST HDL_TAP TRUE
J 0
(-3000 4450);
DISPLAY 0.872340 (-3000 4450);
DISPLAY INVISIBLE (-3000 4450);
FORCEPROP 1 LAST PATH I188
J 0
(-3327 4575);
DISPLAY 0.872340 (-3327 4575);
PAINT GREEN (-3327 4575);
DISPLAY INVISIBLE (-3327 4575);
FORCEADD TAP..1
(-3325 4525);
FORCEPROP 3 LASTPIN (-3375 4525) SIG_NAME M_D_CPU0_SA_DQ<27>
J 0
(-3365 4535);
DISPLAY 0.659574 (-3365 4535);
PAINT MONO (-3365 4535);
DISPLAY INVISIBLE (-3365 4535);
FORCEPROP 1 LASTPIN (-3375 4525) BN 27
J 0
(-3387 4533);
DISPLAY 0.489362 (-3387 4533);
PAINT GREEN (-3387 4533);
FORCEPROP 2 LAST CDS_LIB mstr_standard
J 0
(-3325 4525);
DISPLAY 0.723404 (-3325 4525);
PAINT MONO (-3325 4525);
DISPLAY INVISIBLE (-3325 4525);
FORCEPROP 1 LAST BODY_TYPE PLUMBING
J 0
(-3325 4575);
DISPLAY 0.872340 (-3325 4575);
PAINT GREEN (-3325 4575);
DISPLAY INVISIBLE (-3325 4575);
FORCEPROP 1 LAST HDL_TAP TRUE
J 0
(-3000 4400);
DISPLAY 0.872340 (-3000 4400);
DISPLAY INVISIBLE (-3000 4400);
FORCEPROP 1 LAST PATH I189
J 0
(-3327 4525);
DISPLAY 0.872340 (-3327 4525);
PAINT GREEN (-3327 4525);
DISPLAY INVISIBLE (-3327 4525);
FORCEADD TAP..1
(-3325 4475);
FORCEPROP 3 LASTPIN (-3375 4475) SIG_NAME M_D_CPU0_SA_DQ<28>
J 0
(-3365 4485);
DISPLAY 0.659574 (-3365 4485);
PAINT MONO (-3365 4485);
DISPLAY INVISIBLE (-3365 4485);
FORCEPROP 1 LASTPIN (-3375 4475) BN 28
J 0
(-3387 4483);
DISPLAY 0.489362 (-3387 4483);
PAINT GREEN (-3387 4483);
FORCEPROP 2 LAST CDS_LIB mstr_standard
J 0
(-3325 4475);
DISPLAY 0.723404 (-3325 4475);
PAINT MONO (-3325 4475);
DISPLAY INVISIBLE (-3325 4475);
FORCEPROP 1 LAST BODY_TYPE PLUMBING
J 0
(-3325 4525);
DISPLAY 0.872340 (-3325 4525);
PAINT GREEN (-3325 4525);
DISPLAY INVISIBLE (-3325 4525);
FORCEPROP 1 LAST HDL_TAP TRUE
J 0
(-3000 4350);
DISPLAY 0.872340 (-3000 4350);
DISPLAY INVISIBLE (-3000 4350);
FORCEPROP 1 LAST PATH I190
J 0
(-3327 4475);
DISPLAY 0.872340 (-3327 4475);
PAINT GREEN (-3327 4475);
DISPLAY INVISIBLE (-3327 4475);
FORCEADD TAP..1
(-3325 4375);
FORCEPROP 3 LASTPIN (-3375 4375) SIG_NAME M_D_CPU0_SA_DQ<30>
J 0
(-3365 4385);
DISPLAY 0.659574 (-3365 4385);
PAINT MONO (-3365 4385);
DISPLAY INVISIBLE (-3365 4385);
FORCEPROP 1 LASTPIN (-3375 4375) BN 30
J 0
(-3387 4383);
DISPLAY 0.489362 (-3387 4383);
PAINT GREEN (-3387 4383);
FORCEPROP 2 LAST CDS_LIB mstr_standard
J 0
(-3325 4375);
DISPLAY 0.723404 (-3325 4375);
PAINT MONO (-3325 4375);
DISPLAY INVISIBLE (-3325 4375);
FORCEPROP 1 LAST BODY_TYPE PLUMBING
J 0
(-3325 4425);
DISPLAY 0.872340 (-3325 4425);
PAINT GREEN (-3325 4425);
DISPLAY INVISIBLE (-3325 4425);
FORCEPROP 1 LAST HDL_TAP TRUE
J 0
(-3000 4250);
DISPLAY 0.872340 (-3000 4250);
DISPLAY INVISIBLE (-3000 4250);
FORCEPROP 1 LAST PATH I191
J 0
(-3327 4375);
DISPLAY 0.872340 (-3327 4375);
PAINT GREEN (-3327 4375);
DISPLAY INVISIBLE (-3327 4375);
FORCEADD TAP..1
(-3325 4425);
FORCEPROP 3 LASTPIN (-3375 4425) SIG_NAME M_D_CPU0_SA_DQ<29>
J 0
(-3365 4435);
DISPLAY 0.659574 (-3365 4435);
PAINT MONO (-3365 4435);
DISPLAY INVISIBLE (-3365 4435);
FORCEPROP 1 LASTPIN (-3375 4425) BN 29
J 0
(-3387 4433);
DISPLAY 0.489362 (-3387 4433);
PAINT GREEN (-3387 4433);
FORCEPROP 2 LAST CDS_LIB mstr_standard
J 0
(-3325 4425);
DISPLAY 0.723404 (-3325 4425);
PAINT MONO (-3325 4425);
DISPLAY INVISIBLE (-3325 4425);
FORCEPROP 1 LAST BODY_TYPE PLUMBING
J 0
(-3325 4475);
DISPLAY 0.872340 (-3325 4475);
PAINT GREEN (-3325 4475);
DISPLAY INVISIBLE (-3325 4475);
FORCEPROP 1 LAST HDL_TAP TRUE
J 0
(-3000 4300);
DISPLAY 0.872340 (-3000 4300);
DISPLAY INVISIBLE (-3000 4300);
FORCEPROP 1 LAST PATH I192
J 0
(-3327 4425);
DISPLAY 0.872340 (-3327 4425);
PAINT GREEN (-3327 4425);
DISPLAY INVISIBLE (-3327 4425);
FORCEADD TAP..1
(-3325 4125);
FORCEPROP 3 LASTPIN (-3375 4125) SIG_NAME M_D_CPU0_SB_DQ<2>
J 0
(-3365 4135);
DISPLAY 0.659574 (-3365 4135);
PAINT MONO (-3365 4135);
DISPLAY INVISIBLE (-3365 4135);
FORCEPROP 1 LASTPIN (-3375 4125) BN 2
J 0
(-3387 4133);
DISPLAY 0.489362 (-3387 4133);
PAINT GREEN (-3387 4133);
FORCEPROP 2 LAST CDS_LIB mstr_standard
J 0
(-3325 4125);
DISPLAY 0.723404 (-3325 4125);
PAINT MONO (-3325 4125);
DISPLAY INVISIBLE (-3325 4125);
FORCEPROP 1 LAST BODY_TYPE PLUMBING
J 0
(-3325 4175);
DISPLAY 0.872340 (-3325 4175);
PAINT GREEN (-3325 4175);
DISPLAY INVISIBLE (-3325 4175);
FORCEPROP 1 LAST HDL_TAP TRUE
J 0
(-3000 4000);
DISPLAY 0.872340 (-3000 4000);
DISPLAY INVISIBLE (-3000 4000);
FORCEPROP 1 LAST PATH I193
J 0
(-3327 4125);
DISPLAY 0.872340 (-3327 4125);
PAINT GREEN (-3327 4125);
DISPLAY INVISIBLE (-3327 4125);
FORCEADD TAP..1
(-3325 4225);
FORCEPROP 3 LASTPIN (-3375 4225) SIG_NAME M_D_CPU0_SB_DQ<0>
J 0
(-3365 4235);
DISPLAY 0.659574 (-3365 4235);
PAINT MONO (-3365 4235);
DISPLAY INVISIBLE (-3365 4235);
FORCEPROP 1 LASTPIN (-3375 4225) BN 0
J 0
(-3387 4233);
DISPLAY 0.489362 (-3387 4233);
PAINT GREEN (-3387 4233);
FORCEPROP 2 LAST CDS_LIB mstr_standard
J 0
(-3325 4225);
DISPLAY 0.723404 (-3325 4225);
PAINT MONO (-3325 4225);
DISPLAY INVISIBLE (-3325 4225);
FORCEPROP 1 LAST BODY_TYPE PLUMBING
J 0
(-3325 4275);
DISPLAY 0.872340 (-3325 4275);
PAINT GREEN (-3325 4275);
DISPLAY INVISIBLE (-3325 4275);
FORCEPROP 1 LAST HDL_TAP TRUE
J 0
(-3000 4100);
DISPLAY 0.872340 (-3000 4100);
DISPLAY INVISIBLE (-3000 4100);
FORCEPROP 1 LAST PATH I194
J 0
(-3327 4225);
DISPLAY 0.872340 (-3327 4225);
PAINT GREEN (-3327 4225);
DISPLAY INVISIBLE (-3327 4225);
FORCEADD TAP..1
(-3325 4325);
FORCEPROP 3 LASTPIN (-3375 4325) SIG_NAME M_D_CPU0_SA_DQ<31>
J 0
(-3365 4335);
DISPLAY 0.659574 (-3365 4335);
PAINT MONO (-3365 4335);
DISPLAY INVISIBLE (-3365 4335);
FORCEPROP 1 LASTPIN (-3375 4325) BN 31
J 0
(-3387 4333);
DISPLAY 0.489362 (-3387 4333);
PAINT GREEN (-3387 4333);
FORCEPROP 2 LAST CDS_LIB mstr_standard
J 0
(-3325 4325);
DISPLAY 0.723404 (-3325 4325);
PAINT MONO (-3325 4325);
DISPLAY INVISIBLE (-3325 4325);
FORCEPROP 1 LAST BODY_TYPE PLUMBING
J 0
(-3325 4375);
DISPLAY 0.872340 (-3325 4375);
PAINT GREEN (-3325 4375);
DISPLAY INVISIBLE (-3325 4375);
FORCEPROP 1 LAST HDL_TAP TRUE
J 0
(-3000 4200);
DISPLAY 0.872340 (-3000 4200);
DISPLAY INVISIBLE (-3000 4200);
FORCEPROP 1 LAST PATH I195
J 0
(-3327 4325);
DISPLAY 0.872340 (-3327 4325);
PAINT GREEN (-3327 4325);
DISPLAY INVISIBLE (-3327 4325);
FORCEADD TAP..1
(-3325 4175);
FORCEPROP 3 LASTPIN (-3375 4175) SIG_NAME M_D_CPU0_SB_DQ<1>
J 0
(-3365 4185);
DISPLAY 0.659574 (-3365 4185);
PAINT MONO (-3365 4185);
DISPLAY INVISIBLE (-3365 4185);
FORCEPROP 1 LASTPIN (-3375 4175) BN 1
J 0
(-3387 4183);
DISPLAY 0.489362 (-3387 4183);
PAINT GREEN (-3387 4183);
FORCEPROP 2 LAST CDS_LIB mstr_standard
J 0
(-3325 4175);
DISPLAY 0.723404 (-3325 4175);
PAINT MONO (-3325 4175);
DISPLAY INVISIBLE (-3325 4175);
FORCEPROP 1 LAST BODY_TYPE PLUMBING
J 0
(-3325 4225);
DISPLAY 0.872340 (-3325 4225);
PAINT GREEN (-3325 4225);
DISPLAY INVISIBLE (-3325 4225);
FORCEPROP 1 LAST HDL_TAP TRUE
J 0
(-3000 4050);
DISPLAY 0.872340 (-3000 4050);
DISPLAY INVISIBLE (-3000 4050);
FORCEPROP 1 LAST PATH I196
J 0
(-3327 4175);
DISPLAY 0.872340 (-3327 4175);
PAINT GREEN (-3327 4175);
DISPLAY INVISIBLE (-3327 4175);
FORCEADD OFFPAGE..6
R 2
(-2725 2475);
FORCEPROP 2 LAST $XR0 88 
J 0
(-2511 2475);
DISPLAY 0.638298 (-2511 2475);
PAINT MONO (-2511 2475);
FORCEPROP 2 LAST PATH I197
J 0
(-2500 2525);
DISPLAY 1.021277 (-2500 2525);
DISPLAY INVISIBLE (-2500 2525);
FORCEPROP 1 LAST COMMENT_BODY TRUE
J 2
(-2825 2400);
DISPLAY 0.872340 (-2825 2400);
PAINT GREEN (-2825 2400);
DISPLAY INVISIBLE (-2825 2400);
FORCEPROP 1 LAST OFFPAGE TRUE
J 2
(-3050 2350);
DISPLAY 0.872340 (-3050 2350);
PAINT GREEN (-3050 2350);
DISPLAY INVISIBLE (-3050 2350);
FORCEPROP 2 LAST CDS_LIB mstr_standard
J 2
(-2725 2475);
DISPLAY 0.723404 (-2725 2475);
PAINT MONO (-2725 2475);
DISPLAY INVISIBLE (-2725 2475);
FORCEADD TAP..1
(-3325 3975);
FORCEPROP 3 LASTPIN (-3375 3975) SIG_NAME M_D_CPU0_SB_DQ<5>
J 0
(-3365 3985);
DISPLAY 0.659574 (-3365 3985);
PAINT MONO (-3365 3985);
DISPLAY INVISIBLE (-3365 3985);
FORCEPROP 1 LASTPIN (-3375 3975) BN 5
J 0
(-3387 3983);
DISPLAY 0.489362 (-3387 3983);
PAINT GREEN (-3387 3983);
FORCEPROP 2 LAST CDS_LIB mstr_standard
J 0
(-3325 3975);
DISPLAY 0.723404 (-3325 3975);
PAINT MONO (-3325 3975);
DISPLAY INVISIBLE (-3325 3975);
FORCEPROP 1 LAST BODY_TYPE PLUMBING
J 0
(-3325 4025);
DISPLAY 0.872340 (-3325 4025);
PAINT GREEN (-3325 4025);
DISPLAY INVISIBLE (-3325 4025);
FORCEPROP 1 LAST HDL_TAP TRUE
J 0
(-3000 3850);
DISPLAY 0.872340 (-3000 3850);
DISPLAY INVISIBLE (-3000 3850);
FORCEPROP 1 LAST PATH I198
J 0
(-3327 3975);
DISPLAY 0.872340 (-3327 3975);
PAINT GREEN (-3327 3975);
DISPLAY INVISIBLE (-3327 3975);
FORCEADD TAP..1
(-3325 4075);
FORCEPROP 3 LASTPIN (-3375 4075) SIG_NAME M_D_CPU0_SB_DQ<3>
J 0
(-3365 4085);
DISPLAY 0.659574 (-3365 4085);
PAINT MONO (-3365 4085);
DISPLAY INVISIBLE (-3365 4085);
FORCEPROP 1 LASTPIN (-3375 4075) BN 3
J 0
(-3387 4083);
DISPLAY 0.489362 (-3387 4083);
PAINT GREEN (-3387 4083);
FORCEPROP 2 LAST CDS_LIB mstr_standard
J 0
(-3325 4075);
DISPLAY 0.723404 (-3325 4075);
PAINT MONO (-3325 4075);
DISPLAY INVISIBLE (-3325 4075);
FORCEPROP 1 LAST BODY_TYPE PLUMBING
J 0
(-3325 4125);
DISPLAY 0.872340 (-3325 4125);
PAINT GREEN (-3325 4125);
DISPLAY INVISIBLE (-3325 4125);
FORCEPROP 1 LAST HDL_TAP TRUE
J 0
(-3000 3950);
DISPLAY 0.872340 (-3000 3950);
DISPLAY INVISIBLE (-3000 3950);
FORCEPROP 1 LAST PATH I199
J 0
(-3327 4075);
DISPLAY 0.872340 (-3327 4075);
PAINT GREEN (-3327 4075);
DISPLAY INVISIBLE (-3327 4075);
FORCEADD TAP..1
(-3325 4025);
FORCEPROP 3 LASTPIN (-3375 4025) SIG_NAME M_D_CPU0_SB_DQ<4>
J 0
(-3365 4035);
DISPLAY 0.659574 (-3365 4035);
PAINT MONO (-3365 4035);
DISPLAY INVISIBLE (-3365 4035);
FORCEPROP 1 LASTPIN (-3375 4025) BN 4
J 0
(-3387 4033);
DISPLAY 0.489362 (-3387 4033);
PAINT GREEN (-3387 4033);
FORCEPROP 2 LAST CDS_LIB mstr_standard
J 0
(-3325 4025);
DISPLAY 0.723404 (-3325 4025);
PAINT MONO (-3325 4025);
DISPLAY INVISIBLE (-3325 4025);
FORCEPROP 1 LAST BODY_TYPE PLUMBING
J 0
(-3325 4075);
DISPLAY 0.872340 (-3325 4075);
PAINT GREEN (-3325 4075);
DISPLAY INVISIBLE (-3325 4075);
FORCEPROP 1 LAST HDL_TAP TRUE
J 0
(-3000 3900);
DISPLAY 0.872340 (-3000 3900);
DISPLAY INVISIBLE (-3000 3900);
FORCEPROP 1 LAST PATH I200
J 0
(-3327 4025);
DISPLAY 0.872340 (-3327 4025);
PAINT GREEN (-3327 4025);
DISPLAY INVISIBLE (-3327 4025);
FORCEADD TAP..1
(-3325 3925);
FORCEPROP 3 LASTPIN (-3375 3925) SIG_NAME M_D_CPU0_SB_DQ<6>
J 0
(-3365 3935);
DISPLAY 0.659574 (-3365 3935);
PAINT MONO (-3365 3935);
DISPLAY INVISIBLE (-3365 3935);
FORCEPROP 1 LASTPIN (-3375 3925) BN 6
J 0
(-3387 3933);
DISPLAY 0.489362 (-3387 3933);
PAINT GREEN (-3387 3933);
FORCEPROP 2 LAST CDS_LIB mstr_standard
J 0
(-3325 3925);
DISPLAY 0.723404 (-3325 3925);
PAINT MONO (-3325 3925);
DISPLAY INVISIBLE (-3325 3925);
FORCEPROP 1 LAST BODY_TYPE PLUMBING
J 0
(-3325 3975);
DISPLAY 0.872340 (-3325 3975);
PAINT GREEN (-3325 3975);
DISPLAY INVISIBLE (-3325 3975);
FORCEPROP 1 LAST HDL_TAP TRUE
J 0
(-3000 3800);
DISPLAY 0.872340 (-3000 3800);
DISPLAY INVISIBLE (-3000 3800);
FORCEPROP 1 LAST PATH I201
J 0
(-3327 3925);
DISPLAY 0.872340 (-3327 3925);
PAINT GREEN (-3327 3925);
DISPLAY INVISIBLE (-3327 3925);
FORCEADD TAP..1
(-3325 3875);
FORCEPROP 3 LASTPIN (-3375 3875) SIG_NAME M_D_CPU0_SB_DQ<7>
J 0
(-3365 3885);
DISPLAY 0.659574 (-3365 3885);
PAINT MONO (-3365 3885);
DISPLAY INVISIBLE (-3365 3885);
FORCEPROP 1 LASTPIN (-3375 3875) BN 7
J 0
(-3387 3883);
DISPLAY 0.489362 (-3387 3883);
PAINT GREEN (-3387 3883);
FORCEPROP 2 LAST CDS_LIB mstr_standard
J 0
(-3325 3875);
DISPLAY 0.723404 (-3325 3875);
PAINT MONO (-3325 3875);
DISPLAY INVISIBLE (-3325 3875);
FORCEPROP 1 LAST BODY_TYPE PLUMBING
J 0
(-3325 3925);
DISPLAY 0.872340 (-3325 3925);
PAINT GREEN (-3325 3925);
DISPLAY INVISIBLE (-3325 3925);
FORCEPROP 1 LAST HDL_TAP TRUE
J 0
(-3000 3750);
DISPLAY 0.872340 (-3000 3750);
DISPLAY INVISIBLE (-3000 3750);
FORCEPROP 1 LAST PATH I202
J 0
(-3327 3875);
DISPLAY 0.872340 (-3327 3875);
PAINT GREEN (-3327 3875);
DISPLAY INVISIBLE (-3327 3875);
FORCEADD TAP..1
(-3325 3775);
FORCEPROP 3 LASTPIN (-3375 3775) SIG_NAME M_D_CPU0_SB_DQ<8>
J 0
(-3365 3785);
DISPLAY 0.659574 (-3365 3785);
PAINT MONO (-3365 3785);
DISPLAY INVISIBLE (-3365 3785);
FORCEPROP 1 LASTPIN (-3375 3775) BN 8
J 0
(-3387 3783);
DISPLAY 0.489362 (-3387 3783);
PAINT GREEN (-3387 3783);
FORCEPROP 2 LAST CDS_LIB mstr_standard
J 0
(-3325 3775);
DISPLAY 0.723404 (-3325 3775);
PAINT MONO (-3325 3775);
DISPLAY INVISIBLE (-3325 3775);
FORCEPROP 1 LAST BODY_TYPE PLUMBING
J 0
(-3325 3825);
DISPLAY 0.872340 (-3325 3825);
PAINT GREEN (-3325 3825);
DISPLAY INVISIBLE (-3325 3825);
FORCEPROP 1 LAST HDL_TAP TRUE
J 0
(-3000 3650);
DISPLAY 0.872340 (-3000 3650);
DISPLAY INVISIBLE (-3000 3650);
FORCEPROP 1 LAST PATH I203
J 0
(-3327 3775);
DISPLAY 0.872340 (-3327 3775);
PAINT GREEN (-3327 3775);
DISPLAY INVISIBLE (-3327 3775);
FORCEADD TAP..1
(-3325 3725);
FORCEPROP 3 LASTPIN (-3375 3725) SIG_NAME M_D_CPU0_SB_DQ<9>
J 0
(-3365 3735);
DISPLAY 0.659574 (-3365 3735);
PAINT MONO (-3365 3735);
DISPLAY INVISIBLE (-3365 3735);
FORCEPROP 1 LASTPIN (-3375 3725) BN 9
J 0
(-3387 3733);
DISPLAY 0.489362 (-3387 3733);
PAINT GREEN (-3387 3733);
FORCEPROP 2 LAST CDS_LIB mstr_standard
J 0
(-3325 3725);
DISPLAY 0.723404 (-3325 3725);
PAINT MONO (-3325 3725);
DISPLAY INVISIBLE (-3325 3725);
FORCEPROP 1 LAST BODY_TYPE PLUMBING
J 0
(-3325 3775);
DISPLAY 0.872340 (-3325 3775);
PAINT GREEN (-3325 3775);
DISPLAY INVISIBLE (-3325 3775);
FORCEPROP 1 LAST HDL_TAP TRUE
J 0
(-3000 3600);
DISPLAY 0.872340 (-3000 3600);
DISPLAY INVISIBLE (-3000 3600);
FORCEPROP 1 LAST PATH I204
J 0
(-3327 3725);
DISPLAY 0.872340 (-3327 3725);
PAINT GREEN (-3327 3725);
DISPLAY INVISIBLE (-3327 3725);
FORCEADD TAP..1
(-3325 3675);
FORCEPROP 3 LASTPIN (-3375 3675) SIG_NAME M_D_CPU0_SB_DQ<10>
J 0
(-3365 3685);
DISPLAY 0.659574 (-3365 3685);
PAINT MONO (-3365 3685);
DISPLAY INVISIBLE (-3365 3685);
FORCEPROP 1 LASTPIN (-3375 3675) BN 10
J 0
(-3387 3683);
DISPLAY 0.489362 (-3387 3683);
PAINT GREEN (-3387 3683);
FORCEPROP 2 LAST CDS_LIB mstr_standard
J 0
(-3325 3675);
DISPLAY 0.723404 (-3325 3675);
PAINT MONO (-3325 3675);
DISPLAY INVISIBLE (-3325 3675);
FORCEPROP 1 LAST BODY_TYPE PLUMBING
J 0
(-3325 3725);
DISPLAY 0.872340 (-3325 3725);
PAINT GREEN (-3325 3725);
DISPLAY INVISIBLE (-3325 3725);
FORCEPROP 1 LAST HDL_TAP TRUE
J 0
(-3000 3550);
DISPLAY 0.872340 (-3000 3550);
DISPLAY INVISIBLE (-3000 3550);
FORCEPROP 1 LAST PATH I205
J 0
(-3327 3675);
DISPLAY 0.872340 (-3327 3675);
PAINT GREEN (-3327 3675);
DISPLAY INVISIBLE (-3327 3675);
FORCEADD TAP..1
(-3325 3625);
FORCEPROP 3 LASTPIN (-3375 3625) SIG_NAME M_D_CPU0_SB_DQ<11>
J 0
(-3365 3635);
DISPLAY 0.659574 (-3365 3635);
PAINT MONO (-3365 3635);
DISPLAY INVISIBLE (-3365 3635);
FORCEPROP 1 LASTPIN (-3375 3625) BN 11
J 0
(-3387 3633);
DISPLAY 0.489362 (-3387 3633);
PAINT GREEN (-3387 3633);
FORCEPROP 2 LAST CDS_LIB mstr_standard
J 0
(-3325 3625);
DISPLAY 0.723404 (-3325 3625);
PAINT MONO (-3325 3625);
DISPLAY INVISIBLE (-3325 3625);
FORCEPROP 1 LAST BODY_TYPE PLUMBING
J 0
(-3325 3675);
DISPLAY 0.872340 (-3325 3675);
PAINT GREEN (-3325 3675);
DISPLAY INVISIBLE (-3325 3675);
FORCEPROP 1 LAST HDL_TAP TRUE
J 0
(-3000 3500);
DISPLAY 0.872340 (-3000 3500);
DISPLAY INVISIBLE (-3000 3500);
FORCEPROP 1 LAST PATH I206
J 0
(-3327 3625);
DISPLAY 0.872340 (-3327 3625);
PAINT GREEN (-3327 3625);
DISPLAY INVISIBLE (-3327 3625);
FORCEADD TAP..1
(-3325 3475);
FORCEPROP 3 LASTPIN (-3375 3475) SIG_NAME M_D_CPU0_SB_DQ<14>
J 0
(-3365 3485);
DISPLAY 0.659574 (-3365 3485);
PAINT MONO (-3365 3485);
DISPLAY INVISIBLE (-3365 3485);
FORCEPROP 1 LASTPIN (-3375 3475) BN 14
J 0
(-3387 3483);
DISPLAY 0.489362 (-3387 3483);
PAINT GREEN (-3387 3483);
FORCEPROP 2 LAST CDS_LIB mstr_standard
J 0
(-3325 3475);
DISPLAY 0.723404 (-3325 3475);
PAINT MONO (-3325 3475);
DISPLAY INVISIBLE (-3325 3475);
FORCEPROP 1 LAST BODY_TYPE PLUMBING
J 0
(-3325 3525);
DISPLAY 0.872340 (-3325 3525);
PAINT GREEN (-3325 3525);
DISPLAY INVISIBLE (-3325 3525);
FORCEPROP 1 LAST HDL_TAP TRUE
J 0
(-3000 3350);
DISPLAY 0.872340 (-3000 3350);
DISPLAY INVISIBLE (-3000 3350);
FORCEPROP 1 LAST PATH I207
J 0
(-3327 3475);
DISPLAY 0.872340 (-3327 3475);
PAINT GREEN (-3327 3475);
DISPLAY INVISIBLE (-3327 3475);
FORCEADD TAP..1
(-3325 3575);
FORCEPROP 3 LASTPIN (-3375 3575) SIG_NAME M_D_CPU0_SB_DQ<12>
J 0
(-3365 3585);
DISPLAY 0.659574 (-3365 3585);
PAINT MONO (-3365 3585);
DISPLAY INVISIBLE (-3365 3585);
FORCEPROP 1 LASTPIN (-3375 3575) BN 12
J 0
(-3387 3583);
DISPLAY 0.489362 (-3387 3583);
PAINT GREEN (-3387 3583);
FORCEPROP 2 LAST CDS_LIB mstr_standard
J 0
(-3325 3575);
DISPLAY 0.723404 (-3325 3575);
PAINT MONO (-3325 3575);
DISPLAY INVISIBLE (-3325 3575);
FORCEPROP 1 LAST BODY_TYPE PLUMBING
J 0
(-3325 3625);
DISPLAY 0.872340 (-3325 3625);
PAINT GREEN (-3325 3625);
DISPLAY INVISIBLE (-3325 3625);
FORCEPROP 1 LAST HDL_TAP TRUE
J 0
(-3000 3450);
DISPLAY 0.872340 (-3000 3450);
DISPLAY INVISIBLE (-3000 3450);
FORCEPROP 1 LAST PATH I208
J 0
(-3327 3575);
DISPLAY 0.872340 (-3327 3575);
PAINT GREEN (-3327 3575);
DISPLAY INVISIBLE (-3327 3575);
FORCEADD TAP..1
(-3325 3525);
FORCEPROP 3 LASTPIN (-3375 3525) SIG_NAME M_D_CPU0_SB_DQ<13>
J 0
(-3365 3535);
DISPLAY 0.659574 (-3365 3535);
PAINT MONO (-3365 3535);
DISPLAY INVISIBLE (-3365 3535);
FORCEPROP 1 LASTPIN (-3375 3525) BN 13
J 0
(-3387 3533);
DISPLAY 0.489362 (-3387 3533);
PAINT GREEN (-3387 3533);
FORCEPROP 2 LAST CDS_LIB mstr_standard
J 0
(-3325 3525);
DISPLAY 0.723404 (-3325 3525);
PAINT MONO (-3325 3525);
DISPLAY INVISIBLE (-3325 3525);
FORCEPROP 1 LAST BODY_TYPE PLUMBING
J 0
(-3325 3575);
DISPLAY 0.872340 (-3325 3575);
PAINT GREEN (-3325 3575);
DISPLAY INVISIBLE (-3325 3575);
FORCEPROP 1 LAST HDL_TAP TRUE
J 0
(-3000 3400);
DISPLAY 0.872340 (-3000 3400);
DISPLAY INVISIBLE (-3000 3400);
FORCEPROP 1 LAST PATH I209
J 0
(-3327 3525);
DISPLAY 0.872340 (-3327 3525);
PAINT GREEN (-3327 3525);
DISPLAY INVISIBLE (-3327 3525);
FORCEADD TAP..1
(-3325 3425);
FORCEPROP 3 LASTPIN (-3375 3425) SIG_NAME M_D_CPU0_SB_DQ<15>
J 0
(-3365 3435);
DISPLAY 0.659574 (-3365 3435);
PAINT MONO (-3365 3435);
DISPLAY INVISIBLE (-3365 3435);
FORCEPROP 1 LASTPIN (-3375 3425) BN 15
J 0
(-3387 3433);
DISPLAY 0.489362 (-3387 3433);
PAINT GREEN (-3387 3433);
FORCEPROP 2 LAST CDS_LIB mstr_standard
J 0
(-3325 3425);
DISPLAY 0.723404 (-3325 3425);
PAINT MONO (-3325 3425);
DISPLAY INVISIBLE (-3325 3425);
FORCEPROP 1 LAST BODY_TYPE PLUMBING
J 0
(-3325 3475);
DISPLAY 0.872340 (-3325 3475);
PAINT GREEN (-3325 3475);
DISPLAY INVISIBLE (-3325 3475);
FORCEPROP 1 LAST HDL_TAP TRUE
J 0
(-3000 3300);
DISPLAY 0.872340 (-3000 3300);
DISPLAY INVISIBLE (-3000 3300);
FORCEPROP 1 LAST PATH I210
J 0
(-3327 3425);
DISPLAY 0.872340 (-3327 3425);
PAINT GREEN (-3327 3425);
DISPLAY INVISIBLE (-3327 3425);
FORCEADD TAP..1
(-3325 3225);
FORCEPROP 3 LASTPIN (-3375 3225) SIG_NAME M_D_CPU0_SB_DQ<18>
J 0
(-3365 3235);
DISPLAY 0.659574 (-3365 3235);
PAINT MONO (-3365 3235);
DISPLAY INVISIBLE (-3365 3235);
FORCEPROP 1 LASTPIN (-3375 3225) BN 18
J 0
(-3387 3233);
DISPLAY 0.489362 (-3387 3233);
PAINT GREEN (-3387 3233);
FORCEPROP 2 LAST CDS_LIB mstr_standard
J 0
(-3325 3225);
DISPLAY 0.723404 (-3325 3225);
PAINT MONO (-3325 3225);
DISPLAY INVISIBLE (-3325 3225);
FORCEPROP 1 LAST BODY_TYPE PLUMBING
J 0
(-3325 3275);
DISPLAY 0.872340 (-3325 3275);
PAINT GREEN (-3325 3275);
DISPLAY INVISIBLE (-3325 3275);
FORCEPROP 1 LAST HDL_TAP TRUE
J 0
(-3000 3100);
DISPLAY 0.872340 (-3000 3100);
DISPLAY INVISIBLE (-3000 3100);
FORCEPROP 1 LAST PATH I211
J 0
(-3327 3225);
DISPLAY 0.872340 (-3327 3225);
PAINT GREEN (-3327 3225);
DISPLAY INVISIBLE (-3327 3225);
FORCEADD TAP..1
(-3325 3275);
FORCEPROP 3 LASTPIN (-3375 3275) SIG_NAME M_D_CPU0_SB_DQ<17>
J 0
(-3365 3285);
DISPLAY 0.659574 (-3365 3285);
PAINT MONO (-3365 3285);
DISPLAY INVISIBLE (-3365 3285);
FORCEPROP 1 LASTPIN (-3375 3275) BN 17
J 0
(-3387 3283);
DISPLAY 0.489362 (-3387 3283);
PAINT GREEN (-3387 3283);
FORCEPROP 2 LAST CDS_LIB mstr_standard
J 0
(-3325 3275);
DISPLAY 0.723404 (-3325 3275);
PAINT MONO (-3325 3275);
DISPLAY INVISIBLE (-3325 3275);
FORCEPROP 1 LAST BODY_TYPE PLUMBING
J 0
(-3325 3325);
DISPLAY 0.872340 (-3325 3325);
PAINT GREEN (-3325 3325);
DISPLAY INVISIBLE (-3325 3325);
FORCEPROP 1 LAST HDL_TAP TRUE
J 0
(-3000 3150);
DISPLAY 0.872340 (-3000 3150);
DISPLAY INVISIBLE (-3000 3150);
FORCEPROP 1 LAST PATH I212
J 0
(-3327 3275);
DISPLAY 0.872340 (-3327 3275);
PAINT GREEN (-3327 3275);
DISPLAY INVISIBLE (-3327 3275);
FORCEADD TAP..1
(-3325 3325);
FORCEPROP 3 LASTPIN (-3375 3325) SIG_NAME M_D_CPU0_SB_DQ<16>
J 0
(-3365 3335);
DISPLAY 0.659574 (-3365 3335);
PAINT MONO (-3365 3335);
DISPLAY INVISIBLE (-3365 3335);
FORCEPROP 1 LASTPIN (-3375 3325) BN 16
J 0
(-3387 3333);
DISPLAY 0.489362 (-3387 3333);
PAINT GREEN (-3387 3333);
FORCEPROP 2 LAST CDS_LIB mstr_standard
J 0
(-3325 3325);
DISPLAY 0.723404 (-3325 3325);
PAINT MONO (-3325 3325);
DISPLAY INVISIBLE (-3325 3325);
FORCEPROP 1 LAST BODY_TYPE PLUMBING
J 0
(-3325 3375);
DISPLAY 0.872340 (-3325 3375);
PAINT GREEN (-3325 3375);
DISPLAY INVISIBLE (-3325 3375);
FORCEPROP 1 LAST HDL_TAP TRUE
J 0
(-3000 3200);
DISPLAY 0.872340 (-3000 3200);
DISPLAY INVISIBLE (-3000 3200);
FORCEPROP 1 LAST PATH I213
J 0
(-3327 3325);
DISPLAY 0.872340 (-3327 3325);
PAINT GREEN (-3327 3325);
DISPLAY INVISIBLE (-3327 3325);
FORCEADD TAP..1
(-3325 3075);
FORCEPROP 3 LASTPIN (-3375 3075) SIG_NAME M_D_CPU0_SB_DQ<21>
J 0
(-3365 3085);
DISPLAY 0.659574 (-3365 3085);
PAINT MONO (-3365 3085);
DISPLAY INVISIBLE (-3365 3085);
FORCEPROP 1 LASTPIN (-3375 3075) BN 21
J 0
(-3387 3083);
DISPLAY 0.489362 (-3387 3083);
PAINT GREEN (-3387 3083);
FORCEPROP 2 LAST CDS_LIB mstr_standard
J 0
(-3325 3075);
DISPLAY 0.723404 (-3325 3075);
PAINT MONO (-3325 3075);
DISPLAY INVISIBLE (-3325 3075);
FORCEPROP 1 LAST BODY_TYPE PLUMBING
J 0
(-3325 3125);
DISPLAY 0.872340 (-3325 3125);
PAINT GREEN (-3325 3125);
DISPLAY INVISIBLE (-3325 3125);
FORCEPROP 1 LAST HDL_TAP TRUE
J 0
(-3000 2950);
DISPLAY 0.872340 (-3000 2950);
DISPLAY INVISIBLE (-3000 2950);
FORCEPROP 1 LAST PATH I214
J 0
(-3327 3075);
DISPLAY 0.872340 (-3327 3075);
PAINT GREEN (-3327 3075);
DISPLAY INVISIBLE (-3327 3075);
FORCEADD TAP..1
(-3325 3175);
FORCEPROP 3 LASTPIN (-3375 3175) SIG_NAME M_D_CPU0_SB_DQ<19>
J 0
(-3365 3185);
DISPLAY 0.659574 (-3365 3185);
PAINT MONO (-3365 3185);
DISPLAY INVISIBLE (-3365 3185);
FORCEPROP 1 LASTPIN (-3375 3175) BN 19
J 0
(-3387 3183);
DISPLAY 0.489362 (-3387 3183);
PAINT GREEN (-3387 3183);
FORCEPROP 2 LAST CDS_LIB mstr_standard
J 0
(-3325 3175);
DISPLAY 0.723404 (-3325 3175);
PAINT MONO (-3325 3175);
DISPLAY INVISIBLE (-3325 3175);
FORCEPROP 1 LAST BODY_TYPE PLUMBING
J 0
(-3325 3225);
DISPLAY 0.872340 (-3325 3225);
PAINT GREEN (-3325 3225);
DISPLAY INVISIBLE (-3325 3225);
FORCEPROP 1 LAST HDL_TAP TRUE
J 0
(-3000 3050);
DISPLAY 0.872340 (-3000 3050);
DISPLAY INVISIBLE (-3000 3050);
FORCEPROP 1 LAST PATH I215
J 0
(-3327 3175);
DISPLAY 0.872340 (-3327 3175);
PAINT GREEN (-3327 3175);
DISPLAY INVISIBLE (-3327 3175);
FORCEADD TAP..1
(-3325 3125);
FORCEPROP 3 LASTPIN (-3375 3125) SIG_NAME M_D_CPU0_SB_DQ<20>
J 0
(-3365 3135);
DISPLAY 0.659574 (-3365 3135);
PAINT MONO (-3365 3135);
DISPLAY INVISIBLE (-3365 3135);
FORCEPROP 1 LASTPIN (-3375 3125) BN 20
J 0
(-3387 3133);
DISPLAY 0.489362 (-3387 3133);
PAINT GREEN (-3387 3133);
FORCEPROP 2 LAST CDS_LIB mstr_standard
J 0
(-3325 3125);
DISPLAY 0.723404 (-3325 3125);
PAINT MONO (-3325 3125);
DISPLAY INVISIBLE (-3325 3125);
FORCEPROP 1 LAST BODY_TYPE PLUMBING
J 0
(-3325 3175);
DISPLAY 0.872340 (-3325 3175);
PAINT GREEN (-3325 3175);
DISPLAY INVISIBLE (-3325 3175);
FORCEPROP 1 LAST HDL_TAP TRUE
J 0
(-3000 3000);
DISPLAY 0.872340 (-3000 3000);
DISPLAY INVISIBLE (-3000 3000);
FORCEPROP 1 LAST PATH I216
J 0
(-3327 3125);
DISPLAY 0.872340 (-3327 3125);
PAINT GREEN (-3327 3125);
DISPLAY INVISIBLE (-3327 3125);
FORCEADD TAP..1
(-3325 2975);
FORCEPROP 3 LASTPIN (-3375 2975) SIG_NAME M_D_CPU0_SB_DQ<23>
J 0
(-3365 2985);
DISPLAY 0.659574 (-3365 2985);
PAINT MONO (-3365 2985);
DISPLAY INVISIBLE (-3365 2985);
FORCEPROP 1 LASTPIN (-3375 2975) BN 23
J 0
(-3387 2983);
DISPLAY 0.489362 (-3387 2983);
PAINT GREEN (-3387 2983);
FORCEPROP 2 LAST CDS_LIB mstr_standard
J 0
(-3325 2975);
DISPLAY 0.723404 (-3325 2975);
PAINT MONO (-3325 2975);
DISPLAY INVISIBLE (-3325 2975);
FORCEPROP 1 LAST BODY_TYPE PLUMBING
J 0
(-3325 3025);
DISPLAY 0.872340 (-3325 3025);
PAINT GREEN (-3325 3025);
DISPLAY INVISIBLE (-3325 3025);
FORCEPROP 1 LAST HDL_TAP TRUE
J 0
(-3000 2850);
DISPLAY 0.872340 (-3000 2850);
DISPLAY INVISIBLE (-3000 2850);
FORCEPROP 1 LAST PATH I217
J 0
(-3327 2975);
DISPLAY 0.872340 (-3327 2975);
PAINT GREEN (-3327 2975);
DISPLAY INVISIBLE (-3327 2975);
FORCEADD TAP..1
(-3325 2875);
FORCEPROP 3 LASTPIN (-3375 2875) SIG_NAME M_D_CPU0_SB_DQ<24>
J 0
(-3365 2885);
DISPLAY 0.659574 (-3365 2885);
PAINT MONO (-3365 2885);
DISPLAY INVISIBLE (-3365 2885);
FORCEPROP 1 LASTPIN (-3375 2875) BN 24
J 0
(-3387 2883);
DISPLAY 0.489362 (-3387 2883);
PAINT GREEN (-3387 2883);
FORCEPROP 2 LAST CDS_LIB mstr_standard
J 0
(-3325 2875);
DISPLAY 0.723404 (-3325 2875);
PAINT MONO (-3325 2875);
DISPLAY INVISIBLE (-3325 2875);
FORCEPROP 1 LAST BODY_TYPE PLUMBING
J 0
(-3325 2925);
DISPLAY 0.872340 (-3325 2925);
PAINT GREEN (-3325 2925);
DISPLAY INVISIBLE (-3325 2925);
FORCEPROP 1 LAST HDL_TAP TRUE
J 0
(-3000 2750);
DISPLAY 0.872340 (-3000 2750);
DISPLAY INVISIBLE (-3000 2750);
FORCEPROP 1 LAST PATH I218
J 0
(-3327 2875);
DISPLAY 0.872340 (-3327 2875);
PAINT GREEN (-3327 2875);
DISPLAY INVISIBLE (-3327 2875);
FORCEADD TAP..1
(-3325 3025);
FORCEPROP 3 LASTPIN (-3375 3025) SIG_NAME M_D_CPU0_SB_DQ<22>
J 0
(-3365 3035);
DISPLAY 0.659574 (-3365 3035);
PAINT MONO (-3365 3035);
DISPLAY INVISIBLE (-3365 3035);
FORCEPROP 1 LASTPIN (-3375 3025) BN 22
J 0
(-3387 3033);
DISPLAY 0.489362 (-3387 3033);
PAINT GREEN (-3387 3033);
FORCEPROP 2 LAST CDS_LIB mstr_standard
J 0
(-3325 3025);
DISPLAY 0.723404 (-3325 3025);
PAINT MONO (-3325 3025);
DISPLAY INVISIBLE (-3325 3025);
FORCEPROP 1 LAST BODY_TYPE PLUMBING
J 0
(-3325 3075);
DISPLAY 0.872340 (-3325 3075);
PAINT GREEN (-3325 3075);
DISPLAY INVISIBLE (-3325 3075);
FORCEPROP 1 LAST HDL_TAP TRUE
J 0
(-3000 2900);
DISPLAY 0.872340 (-3000 2900);
DISPLAY INVISIBLE (-3000 2900);
FORCEPROP 1 LAST PATH I219
J 0
(-3327 3025);
DISPLAY 0.872340 (-3327 3025);
PAINT GREEN (-3327 3025);
DISPLAY INVISIBLE (-3327 3025);
FORCEADD TAP..1
(-3325 2825);
FORCEPROP 3 LASTPIN (-3375 2825) SIG_NAME M_D_CPU0_SB_DQ<25>
J 0
(-3365 2835);
DISPLAY 0.659574 (-3365 2835);
PAINT MONO (-3365 2835);
DISPLAY INVISIBLE (-3365 2835);
FORCEPROP 1 LASTPIN (-3375 2825) BN 25
J 0
(-3387 2833);
DISPLAY 0.489362 (-3387 2833);
PAINT GREEN (-3387 2833);
FORCEPROP 2 LAST CDS_LIB mstr_standard
J 0
(-3325 2825);
DISPLAY 0.723404 (-3325 2825);
PAINT MONO (-3325 2825);
DISPLAY INVISIBLE (-3325 2825);
FORCEPROP 1 LAST BODY_TYPE PLUMBING
J 0
(-3325 2875);
DISPLAY 0.872340 (-3325 2875);
PAINT GREEN (-3325 2875);
DISPLAY INVISIBLE (-3325 2875);
FORCEPROP 1 LAST HDL_TAP TRUE
J 0
(-3000 2700);
DISPLAY 0.872340 (-3000 2700);
DISPLAY INVISIBLE (-3000 2700);
FORCEPROP 1 LAST PATH I220
J 0
(-3327 2825);
DISPLAY 0.872340 (-3327 2825);
PAINT GREEN (-3327 2825);
DISPLAY INVISIBLE (-3327 2825);
FORCEADD TAP..1
(-3325 2775);
FORCEPROP 3 LASTPIN (-3375 2775) SIG_NAME M_D_CPU0_SB_DQ<26>
J 0
(-3365 2785);
DISPLAY 0.659574 (-3365 2785);
PAINT MONO (-3365 2785);
DISPLAY INVISIBLE (-3365 2785);
FORCEPROP 1 LASTPIN (-3375 2775) BN 26
J 0
(-3387 2783);
DISPLAY 0.489362 (-3387 2783);
PAINT GREEN (-3387 2783);
FORCEPROP 2 LAST CDS_LIB mstr_standard
J 0
(-3325 2775);
DISPLAY 0.723404 (-3325 2775);
PAINT MONO (-3325 2775);
DISPLAY INVISIBLE (-3325 2775);
FORCEPROP 1 LAST BODY_TYPE PLUMBING
J 0
(-3325 2825);
DISPLAY 0.872340 (-3325 2825);
PAINT GREEN (-3325 2825);
DISPLAY INVISIBLE (-3325 2825);
FORCEPROP 1 LAST HDL_TAP TRUE
J 0
(-3000 2650);
DISPLAY 0.872340 (-3000 2650);
DISPLAY INVISIBLE (-3000 2650);
FORCEPROP 1 LAST PATH I221
J 0
(-3327 2775);
DISPLAY 0.872340 (-3327 2775);
PAINT GREEN (-3327 2775);
DISPLAY INVISIBLE (-3327 2775);
FORCEADD TAP..1
(-3325 2725);
FORCEPROP 3 LASTPIN (-3375 2725) SIG_NAME M_D_CPU0_SB_DQ<27>
J 0
(-3365 2735);
DISPLAY 0.659574 (-3365 2735);
PAINT MONO (-3365 2735);
DISPLAY INVISIBLE (-3365 2735);
FORCEPROP 1 LASTPIN (-3375 2725) BN 27
J 0
(-3387 2733);
DISPLAY 0.489362 (-3387 2733);
PAINT GREEN (-3387 2733);
FORCEPROP 2 LAST CDS_LIB mstr_standard
J 0
(-3325 2725);
DISPLAY 0.723404 (-3325 2725);
PAINT MONO (-3325 2725);
DISPLAY INVISIBLE (-3325 2725);
FORCEPROP 1 LAST BODY_TYPE PLUMBING
J 0
(-3325 2775);
DISPLAY 0.872340 (-3325 2775);
PAINT GREEN (-3325 2775);
DISPLAY INVISIBLE (-3325 2775);
FORCEPROP 1 LAST HDL_TAP TRUE
J 0
(-3000 2600);
DISPLAY 0.872340 (-3000 2600);
DISPLAY INVISIBLE (-3000 2600);
FORCEPROP 1 LAST PATH I222
J 0
(-3327 2725);
DISPLAY 0.872340 (-3327 2725);
PAINT GREEN (-3327 2725);
DISPLAY INVISIBLE (-3327 2725);
FORCEADD TAP..1
(-3325 2675);
FORCEPROP 3 LASTPIN (-3375 2675) SIG_NAME M_D_CPU0_SB_DQ<28>
J 0
(-3365 2685);
DISPLAY 0.659574 (-3365 2685);
PAINT MONO (-3365 2685);
DISPLAY INVISIBLE (-3365 2685);
FORCEPROP 1 LASTPIN (-3375 2675) BN 28
J 0
(-3387 2683);
DISPLAY 0.489362 (-3387 2683);
PAINT GREEN (-3387 2683);
FORCEPROP 2 LAST CDS_LIB mstr_standard
J 0
(-3325 2675);
DISPLAY 0.723404 (-3325 2675);
PAINT MONO (-3325 2675);
DISPLAY INVISIBLE (-3325 2675);
FORCEPROP 1 LAST BODY_TYPE PLUMBING
J 0
(-3325 2725);
DISPLAY 0.872340 (-3325 2725);
PAINT GREEN (-3325 2725);
DISPLAY INVISIBLE (-3325 2725);
FORCEPROP 1 LAST HDL_TAP TRUE
J 0
(-3000 2550);
DISPLAY 0.872340 (-3000 2550);
DISPLAY INVISIBLE (-3000 2550);
FORCEPROP 1 LAST PATH I223
J 0
(-3327 2675);
DISPLAY 0.872340 (-3327 2675);
PAINT GREEN (-3327 2675);
DISPLAY INVISIBLE (-3327 2675);
FORCEADD TAP..1
(-3325 2575);
FORCEPROP 3 LASTPIN (-3375 2575) SIG_NAME M_D_CPU0_SB_DQ<30>
J 0
(-3365 2585);
DISPLAY 0.659574 (-3365 2585);
PAINT MONO (-3365 2585);
DISPLAY INVISIBLE (-3365 2585);
FORCEPROP 1 LASTPIN (-3375 2575) BN 30
J 0
(-3387 2583);
DISPLAY 0.489362 (-3387 2583);
PAINT GREEN (-3387 2583);
FORCEPROP 2 LAST CDS_LIB mstr_standard
J 0
(-3325 2575);
DISPLAY 0.723404 (-3325 2575);
PAINT MONO (-3325 2575);
DISPLAY INVISIBLE (-3325 2575);
FORCEPROP 1 LAST BODY_TYPE PLUMBING
J 0
(-3325 2625);
DISPLAY 0.872340 (-3325 2625);
PAINT GREEN (-3325 2625);
DISPLAY INVISIBLE (-3325 2625);
FORCEPROP 1 LAST HDL_TAP TRUE
J 0
(-3000 2450);
DISPLAY 0.872340 (-3000 2450);
DISPLAY INVISIBLE (-3000 2450);
FORCEPROP 1 LAST PATH I224
J 0
(-3327 2575);
DISPLAY 0.872340 (-3327 2575);
PAINT GREEN (-3327 2575);
DISPLAY INVISIBLE (-3327 2575);
FORCEADD TAP..1
(-3325 2625);
FORCEPROP 3 LASTPIN (-3375 2625) SIG_NAME M_D_CPU0_SB_DQ<29>
J 0
(-3365 2635);
DISPLAY 0.659574 (-3365 2635);
PAINT MONO (-3365 2635);
DISPLAY INVISIBLE (-3365 2635);
FORCEPROP 1 LASTPIN (-3375 2625) BN 29
J 0
(-3387 2633);
DISPLAY 0.489362 (-3387 2633);
PAINT GREEN (-3387 2633);
FORCEPROP 2 LAST CDS_LIB mstr_standard
J 0
(-3325 2625);
DISPLAY 0.723404 (-3325 2625);
PAINT MONO (-3325 2625);
DISPLAY INVISIBLE (-3325 2625);
FORCEPROP 1 LAST BODY_TYPE PLUMBING
J 0
(-3325 2675);
DISPLAY 0.872340 (-3325 2675);
PAINT GREEN (-3325 2675);
DISPLAY INVISIBLE (-3325 2675);
FORCEPROP 1 LAST HDL_TAP TRUE
J 0
(-3000 2500);
DISPLAY 0.872340 (-3000 2500);
DISPLAY INVISIBLE (-3000 2500);
FORCEPROP 1 LAST PATH I225
J 0
(-3327 2625);
DISPLAY 0.872340 (-3327 2625);
PAINT GREEN (-3327 2625);
DISPLAY INVISIBLE (-3327 2625);
FORCEADD TAP..1
(-3325 2325);
FORCEPROP 3 LASTPIN (-3375 2325) SIG_NAME M_D_CPU0_SA_CB<2>
J 0
(-3365 2335);
DISPLAY 0.659574 (-3365 2335);
PAINT MONO (-3365 2335);
DISPLAY INVISIBLE (-3365 2335);
FORCEPROP 1 LASTPIN (-3375 2325) BN 2
J 0
(-3387 2333);
DISPLAY 0.489362 (-3387 2333);
PAINT GREEN (-3387 2333);
FORCEPROP 2 LAST CDS_LIB mstr_standard
J 2
(-3325 2325);
DISPLAY 0.723404 (-3325 2325);
PAINT MONO (-3325 2325);
DISPLAY INVISIBLE (-3325 2325);
FORCEPROP 1 LAST BODY_TYPE PLUMBING
J 0
(-3325 2375);
DISPLAY 0.872340 (-3325 2375);
PAINT GREEN (-3325 2375);
DISPLAY INVISIBLE (-3325 2375);
FORCEPROP 1 LAST HDL_TAP TRUE
J 0
(-3000 2200);
DISPLAY 0.872340 (-3000 2200);
DISPLAY INVISIBLE (-3000 2200);
FORCEPROP 1 LAST PATH I226
J 0
(-3327 2325);
DISPLAY 0.872340 (-3327 2325);
PAINT GREEN (-3327 2325);
DISPLAY INVISIBLE (-3327 2325);
FORCEADD TAP..1
(-3325 2375);
FORCEPROP 3 LASTPIN (-3375 2375) SIG_NAME M_D_CPU0_SA_CB<1>
J 0
(-3365 2385);
DISPLAY 0.659574 (-3365 2385);
PAINT MONO (-3365 2385);
DISPLAY INVISIBLE (-3365 2385);
FORCEPROP 1 LASTPIN (-3375 2375) BN 1
J 0
(-3387 2383);
DISPLAY 0.489362 (-3387 2383);
PAINT GREEN (-3387 2383);
FORCEPROP 2 LAST CDS_LIB mstr_standard
J 2
(-3325 2375);
DISPLAY 0.723404 (-3325 2375);
PAINT MONO (-3325 2375);
DISPLAY INVISIBLE (-3325 2375);
FORCEPROP 1 LAST BODY_TYPE PLUMBING
J 0
(-3325 2425);
DISPLAY 0.872340 (-3325 2425);
PAINT GREEN (-3325 2425);
DISPLAY INVISIBLE (-3325 2425);
FORCEPROP 1 LAST HDL_TAP TRUE
J 0
(-3000 2250);
DISPLAY 0.872340 (-3000 2250);
DISPLAY INVISIBLE (-3000 2250);
FORCEPROP 1 LAST PATH I227
J 0
(-3327 2375);
DISPLAY 0.872340 (-3327 2375);
PAINT GREEN (-3327 2375);
DISPLAY INVISIBLE (-3327 2375);
FORCEADD TAP..1
(-3325 2425);
FORCEPROP 3 LASTPIN (-3375 2425) SIG_NAME M_D_CPU0_SA_CB<0>
J 0
(-3365 2435);
DISPLAY 0.659574 (-3365 2435);
PAINT MONO (-3365 2435);
DISPLAY INVISIBLE (-3365 2435);
FORCEPROP 1 LASTPIN (-3375 2425) BN 0
J 0
(-3387 2433);
DISPLAY 0.489362 (-3387 2433);
PAINT GREEN (-3387 2433);
FORCEPROP 2 LAST CDS_LIB mstr_standard
J 2
(-3325 2425);
DISPLAY 0.723404 (-3325 2425);
PAINT MONO (-3325 2425);
DISPLAY INVISIBLE (-3325 2425);
FORCEPROP 1 LAST BODY_TYPE PLUMBING
J 0
(-3325 2475);
DISPLAY 0.872340 (-3325 2475);
PAINT GREEN (-3325 2475);
DISPLAY INVISIBLE (-3325 2475);
FORCEPROP 1 LAST HDL_TAP TRUE
J 0
(-3000 2300);
DISPLAY 0.872340 (-3000 2300);
DISPLAY INVISIBLE (-3000 2300);
FORCEPROP 1 LAST PATH I228
J 0
(-3327 2425);
DISPLAY 0.872340 (-3327 2425);
PAINT GREEN (-3327 2425);
DISPLAY INVISIBLE (-3327 2425);
FORCEADD TAP..1
(-3325 2525);
FORCEPROP 3 LASTPIN (-3375 2525) SIG_NAME M_D_CPU0_SB_DQ<31>
J 0
(-3365 2535);
DISPLAY 0.659574 (-3365 2535);
PAINT MONO (-3365 2535);
DISPLAY INVISIBLE (-3365 2535);
FORCEPROP 1 LASTPIN (-3375 2525) BN 31
J 0
(-3387 2533);
DISPLAY 0.489362 (-3387 2533);
PAINT GREEN (-3387 2533);
FORCEPROP 2 LAST CDS_LIB mstr_standard
J 0
(-3325 2525);
DISPLAY 0.723404 (-3325 2525);
PAINT MONO (-3325 2525);
DISPLAY INVISIBLE (-3325 2525);
FORCEPROP 1 LAST BODY_TYPE PLUMBING
J 0
(-3325 2575);
DISPLAY 0.872340 (-3325 2575);
PAINT GREEN (-3325 2575);
DISPLAY INVISIBLE (-3325 2575);
FORCEPROP 1 LAST HDL_TAP TRUE
J 0
(-3000 2400);
DISPLAY 0.872340 (-3000 2400);
DISPLAY INVISIBLE (-3000 2400);
FORCEPROP 1 LAST PATH I229
J 0
(-3327 2525);
DISPLAY 0.872340 (-3327 2525);
PAINT GREEN (-3327 2525);
DISPLAY INVISIBLE (-3327 2525);
FORCEADD TAP..1
(-3325 2225);
FORCEPROP 3 LASTPIN (-3375 2225) SIG_NAME M_D_CPU0_SA_CB<4>
J 0
(-3365 2235);
DISPLAY 0.659574 (-3365 2235);
PAINT MONO (-3365 2235);
DISPLAY INVISIBLE (-3365 2235);
FORCEPROP 1 LASTPIN (-3375 2225) BN 4
J 0
(-3387 2233);
DISPLAY 0.489362 (-3387 2233);
PAINT GREEN (-3387 2233);
FORCEPROP 2 LAST CDS_LIB mstr_standard
J 2
(-3325 2225);
DISPLAY 0.723404 (-3325 2225);
PAINT MONO (-3325 2225);
DISPLAY INVISIBLE (-3325 2225);
FORCEPROP 1 LAST BODY_TYPE PLUMBING
J 0
(-3325 2275);
DISPLAY 0.872340 (-3325 2275);
PAINT GREEN (-3325 2275);
DISPLAY INVISIBLE (-3325 2275);
FORCEPROP 1 LAST HDL_TAP TRUE
J 0
(-3000 2100);
DISPLAY 0.872340 (-3000 2100);
DISPLAY INVISIBLE (-3000 2100);
FORCEPROP 1 LAST PATH I230
J 0
(-3327 2225);
DISPLAY 0.872340 (-3327 2225);
PAINT GREEN (-3327 2225);
DISPLAY INVISIBLE (-3327 2225);
FORCEADD TAP..1
(-3325 2275);
FORCEPROP 3 LASTPIN (-3375 2275) SIG_NAME M_D_CPU0_SA_CB<3>
J 0
(-3365 2285);
DISPLAY 0.659574 (-3365 2285);
PAINT MONO (-3365 2285);
DISPLAY INVISIBLE (-3365 2285);
FORCEPROP 1 LASTPIN (-3375 2275) BN 3
J 0
(-3387 2283);
DISPLAY 0.489362 (-3387 2283);
PAINT GREEN (-3387 2283);
FORCEPROP 2 LAST CDS_LIB mstr_standard
J 2
(-3325 2275);
DISPLAY 0.723404 (-3325 2275);
PAINT MONO (-3325 2275);
DISPLAY INVISIBLE (-3325 2275);
FORCEPROP 1 LAST BODY_TYPE PLUMBING
J 0
(-3325 2325);
DISPLAY 0.872340 (-3325 2325);
PAINT GREEN (-3325 2325);
DISPLAY INVISIBLE (-3325 2325);
FORCEPROP 1 LAST HDL_TAP TRUE
J 0
(-3000 2150);
DISPLAY 0.872340 (-3000 2150);
DISPLAY INVISIBLE (-3000 2150);
FORCEPROP 1 LAST PATH I231
J 0
(-3327 2275);
DISPLAY 0.872340 (-3327 2275);
PAINT GREEN (-3327 2275);
DISPLAY INVISIBLE (-3327 2275);
FORCEADD TAP..1
(-3325 2175);
FORCEPROP 3 LASTPIN (-3375 2175) SIG_NAME M_D_CPU0_SA_CB<5>
J 0
(-3365 2185);
DISPLAY 0.659574 (-3365 2185);
PAINT MONO (-3365 2185);
DISPLAY INVISIBLE (-3365 2185);
FORCEPROP 1 LASTPIN (-3375 2175) BN 5
J 0
(-3387 2183);
DISPLAY 0.489362 (-3387 2183);
PAINT GREEN (-3387 2183);
FORCEPROP 2 LAST CDS_LIB mstr_standard
J 2
(-3325 2175);
DISPLAY 0.723404 (-3325 2175);
PAINT MONO (-3325 2175);
DISPLAY INVISIBLE (-3325 2175);
FORCEPROP 1 LAST BODY_TYPE PLUMBING
J 0
(-3325 2225);
DISPLAY 0.872340 (-3325 2225);
PAINT GREEN (-3325 2225);
DISPLAY INVISIBLE (-3325 2225);
FORCEPROP 1 LAST HDL_TAP TRUE
J 0
(-3000 2050);
DISPLAY 0.872340 (-3000 2050);
DISPLAY INVISIBLE (-3000 2050);
FORCEPROP 1 LAST PATH I232
J 0
(-3327 2175);
DISPLAY 0.872340 (-3327 2175);
PAINT GREEN (-3327 2175);
DISPLAY INVISIBLE (-3327 2175);
FORCEADD TAP..1
(-3325 2125);
FORCEPROP 3 LASTPIN (-3375 2125) SIG_NAME M_D_CPU0_SA_CB<6>
J 0
(-3365 2135);
DISPLAY 0.659574 (-3365 2135);
PAINT MONO (-3365 2135);
DISPLAY INVISIBLE (-3365 2135);
FORCEPROP 1 LASTPIN (-3375 2125) BN 6
J 0
(-3387 2133);
DISPLAY 0.489362 (-3387 2133);
PAINT GREEN (-3387 2133);
FORCEPROP 2 LAST CDS_LIB mstr_standard
J 2
(-3325 2125);
DISPLAY 0.723404 (-3325 2125);
PAINT MONO (-3325 2125);
DISPLAY INVISIBLE (-3325 2125);
FORCEPROP 1 LAST BODY_TYPE PLUMBING
J 0
(-3325 2175);
DISPLAY 0.872340 (-3325 2175);
PAINT GREEN (-3325 2175);
DISPLAY INVISIBLE (-3325 2175);
FORCEPROP 1 LAST HDL_TAP TRUE
J 0
(-3000 2000);
DISPLAY 0.872340 (-3000 2000);
DISPLAY INVISIBLE (-3000 2000);
FORCEPROP 1 LAST PATH I233
J 0
(-3327 2125);
DISPLAY 0.872340 (-3327 2125);
PAINT GREEN (-3327 2125);
DISPLAY INVISIBLE (-3327 2125);
FORCEADD TAP..1
(-3325 2075);
FORCEPROP 3 LASTPIN (-3375 2075) SIG_NAME M_D_CPU0_SA_CB<7>
J 0
(-3365 2085);
DISPLAY 0.659574 (-3365 2085);
PAINT MONO (-3365 2085);
DISPLAY INVISIBLE (-3365 2085);
FORCEPROP 1 LASTPIN (-3375 2075) BN 7
J 0
(-3387 2083);
DISPLAY 0.489362 (-3387 2083);
PAINT GREEN (-3387 2083);
FORCEPROP 2 LAST CDS_LIB mstr_standard
J 2
(-3325 2075);
DISPLAY 0.723404 (-3325 2075);
PAINT MONO (-3325 2075);
DISPLAY INVISIBLE (-3325 2075);
FORCEPROP 1 LAST BODY_TYPE PLUMBING
J 0
(-3325 2125);
DISPLAY 0.872340 (-3325 2125);
PAINT GREEN (-3325 2125);
DISPLAY INVISIBLE (-3325 2125);
FORCEPROP 1 LAST HDL_TAP TRUE
J 0
(-3000 1950);
DISPLAY 0.872340 (-3000 1950);
DISPLAY INVISIBLE (-3000 1950);
FORCEPROP 1 LAST PATH I234
J 0
(-3327 2075);
DISPLAY 0.872340 (-3327 2075);
PAINT GREEN (-3327 2075);
DISPLAY INVISIBLE (-3327 2075);
FORCEADD OFFPAGE..6
R 2
(-2725 2025);
FORCEPROP 2 LAST $XR0 88 
J 0
(-2511 2025);
DISPLAY 0.638298 (-2511 2025);
PAINT MONO (-2511 2025);
FORCEPROP 2 LAST PATH I235
J 0
(-2500 2075);
DISPLAY 1.021277 (-2500 2075);
DISPLAY INVISIBLE (-2500 2075);
FORCEPROP 1 LAST COMMENT_BODY TRUE
J 2
(-2825 1950);
DISPLAY 0.872340 (-2825 1950);
PAINT GREEN (-2825 1950);
DISPLAY INVISIBLE (-2825 1950);
FORCEPROP 1 LAST OFFPAGE TRUE
J 2
(-3050 1900);
DISPLAY 0.872340 (-3050 1900);
PAINT GREEN (-3050 1900);
DISPLAY INVISIBLE (-3050 1900);
FORCEPROP 2 LAST CDS_LIB mstr_standard
J 2
(-2725 2025);
DISPLAY 0.723404 (-2725 2025);
PAINT MONO (-2725 2025);
DISPLAY INVISIBLE (-2725 2025);
FORCEADD TAP..1
(-3325 1825);
FORCEPROP 3 LASTPIN (-3375 1825) SIG_NAME M_D_CPU0_SB_CB<3>
J 0
(-3365 1835);
DISPLAY 0.659574 (-3365 1835);
PAINT MONO (-3365 1835);
DISPLAY INVISIBLE (-3365 1835);
FORCEPROP 1 LASTPIN (-3375 1825) BN 3
J 0
(-3387 1833);
DISPLAY 0.489362 (-3387 1833);
PAINT GREEN (-3387 1833);
FORCEPROP 2 LAST CDS_LIB mstr_standard
J 2
(-3325 1825);
DISPLAY 0.723404 (-3325 1825);
PAINT MONO (-3325 1825);
DISPLAY INVISIBLE (-3325 1825);
FORCEPROP 1 LAST BODY_TYPE PLUMBING
J 0
(-3325 1875);
DISPLAY 0.872340 (-3325 1875);
PAINT GREEN (-3325 1875);
DISPLAY INVISIBLE (-3325 1875);
FORCEPROP 1 LAST HDL_TAP TRUE
J 0
(-3000 1700);
DISPLAY 0.872340 (-3000 1700);
DISPLAY INVISIBLE (-3000 1700);
FORCEPROP 1 LAST PATH I236
J 0
(-3327 1825);
DISPLAY 0.872340 (-3327 1825);
PAINT GREEN (-3327 1825);
DISPLAY INVISIBLE (-3327 1825);
FORCEADD TAP..1
(-3325 1875);
FORCEPROP 3 LASTPIN (-3375 1875) SIG_NAME M_D_CPU0_SB_CB<2>
J 0
(-3365 1885);
DISPLAY 0.659574 (-3365 1885);
PAINT MONO (-3365 1885);
DISPLAY INVISIBLE (-3365 1885);
FORCEPROP 1 LASTPIN (-3375 1875) BN 2
J 0
(-3387 1883);
DISPLAY 0.489362 (-3387 1883);
PAINT GREEN (-3387 1883);
FORCEPROP 2 LAST CDS_LIB mstr_standard
J 2
(-3325 1875);
DISPLAY 0.723404 (-3325 1875);
PAINT MONO (-3325 1875);
DISPLAY INVISIBLE (-3325 1875);
FORCEPROP 1 LAST BODY_TYPE PLUMBING
J 0
(-3325 1925);
DISPLAY 0.872340 (-3325 1925);
PAINT GREEN (-3325 1925);
DISPLAY INVISIBLE (-3325 1925);
FORCEPROP 1 LAST HDL_TAP TRUE
J 0
(-3000 1750);
DISPLAY 0.872340 (-3000 1750);
DISPLAY INVISIBLE (-3000 1750);
FORCEPROP 1 LAST PATH I237
J 0
(-3327 1875);
DISPLAY 0.872340 (-3327 1875);
PAINT GREEN (-3327 1875);
DISPLAY INVISIBLE (-3327 1875);
FORCEADD TAP..1
(-3325 1975);
FORCEPROP 3 LASTPIN (-3375 1975) SIG_NAME M_D_CPU0_SB_CB<0>
J 0
(-3365 1985);
DISPLAY 0.659574 (-3365 1985);
PAINT MONO (-3365 1985);
DISPLAY INVISIBLE (-3365 1985);
FORCEPROP 1 LASTPIN (-3375 1975) BN 0
J 0
(-3387 1983);
DISPLAY 0.489362 (-3387 1983);
PAINT GREEN (-3387 1983);
FORCEPROP 2 LAST CDS_LIB mstr_standard
J 2
(-3325 1975);
DISPLAY 0.723404 (-3325 1975);
PAINT MONO (-3325 1975);
DISPLAY INVISIBLE (-3325 1975);
FORCEPROP 1 LAST BODY_TYPE PLUMBING
J 0
(-3325 2025);
DISPLAY 0.872340 (-3325 2025);
PAINT GREEN (-3325 2025);
DISPLAY INVISIBLE (-3325 2025);
FORCEPROP 1 LAST HDL_TAP TRUE
J 0
(-3000 1850);
DISPLAY 0.872340 (-3000 1850);
DISPLAY INVISIBLE (-3000 1850);
FORCEPROP 1 LAST PATH I238
J 0
(-3327 1975);
DISPLAY 0.872340 (-3327 1975);
PAINT GREEN (-3327 1975);
DISPLAY INVISIBLE (-3327 1975);
FORCEADD TAP..1
(-3325 1925);
FORCEPROP 3 LASTPIN (-3375 1925) SIG_NAME M_D_CPU0_SB_CB<1>
J 0
(-3365 1935);
DISPLAY 0.659574 (-3365 1935);
PAINT MONO (-3365 1935);
DISPLAY INVISIBLE (-3365 1935);
FORCEPROP 1 LASTPIN (-3375 1925) BN 1
J 0
(-3387 1933);
DISPLAY 0.489362 (-3387 1933);
PAINT GREEN (-3387 1933);
FORCEPROP 2 LAST CDS_LIB mstr_standard
J 2
(-3325 1925);
DISPLAY 0.723404 (-3325 1925);
PAINT MONO (-3325 1925);
DISPLAY INVISIBLE (-3325 1925);
FORCEPROP 1 LAST BODY_TYPE PLUMBING
J 0
(-3325 1975);
DISPLAY 0.872340 (-3325 1975);
PAINT GREEN (-3325 1975);
DISPLAY INVISIBLE (-3325 1975);
FORCEPROP 1 LAST HDL_TAP TRUE
J 0
(-3000 1800);
DISPLAY 0.872340 (-3000 1800);
DISPLAY INVISIBLE (-3000 1800);
FORCEPROP 1 LAST PATH I239
J 0
(-3327 1925);
DISPLAY 0.872340 (-3327 1925);
PAINT GREEN (-3327 1925);
DISPLAY INVISIBLE (-3327 1925);
FORCEADD TAP..1
(-3325 1675);
FORCEPROP 3 LASTPIN (-3375 1675) SIG_NAME M_D_CPU0_SB_CB<6>
J 0
(-3365 1685);
DISPLAY 0.659574 (-3365 1685);
PAINT MONO (-3365 1685);
DISPLAY INVISIBLE (-3365 1685);
FORCEPROP 1 LASTPIN (-3375 1675) BN 6
J 0
(-3387 1683);
DISPLAY 0.489362 (-3387 1683);
PAINT GREEN (-3387 1683);
FORCEPROP 2 LAST CDS_LIB mstr_standard
J 2
(-3325 1675);
DISPLAY 0.723404 (-3325 1675);
PAINT MONO (-3325 1675);
DISPLAY INVISIBLE (-3325 1675);
FORCEPROP 1 LAST BODY_TYPE PLUMBING
J 0
(-3325 1725);
DISPLAY 0.872340 (-3325 1725);
PAINT GREEN (-3325 1725);
DISPLAY INVISIBLE (-3325 1725);
FORCEPROP 1 LAST HDL_TAP TRUE
J 0
(-3000 1550);
DISPLAY 0.872340 (-3000 1550);
DISPLAY INVISIBLE (-3000 1550);
FORCEPROP 1 LAST PATH I240
J 0
(-3327 1675);
DISPLAY 0.872340 (-3327 1675);
PAINT GREEN (-3327 1675);
DISPLAY INVISIBLE (-3327 1675);
FORCEADD TAP..1
(-3325 1775);
FORCEPROP 3 LASTPIN (-3375 1775) SIG_NAME M_D_CPU0_SB_CB<4>
J 0
(-3365 1785);
DISPLAY 0.659574 (-3365 1785);
PAINT MONO (-3365 1785);
DISPLAY INVISIBLE (-3365 1785);
FORCEPROP 1 LASTPIN (-3375 1775) BN 4
J 0
(-3387 1783);
DISPLAY 0.489362 (-3387 1783);
PAINT GREEN (-3387 1783);
FORCEPROP 2 LAST CDS_LIB mstr_standard
J 2
(-3325 1775);
DISPLAY 0.723404 (-3325 1775);
PAINT MONO (-3325 1775);
DISPLAY INVISIBLE (-3325 1775);
FORCEPROP 1 LAST BODY_TYPE PLUMBING
J 0
(-3325 1825);
DISPLAY 0.872340 (-3325 1825);
PAINT GREEN (-3325 1825);
DISPLAY INVISIBLE (-3325 1825);
FORCEPROP 1 LAST HDL_TAP TRUE
J 0
(-3000 1650);
DISPLAY 0.872340 (-3000 1650);
DISPLAY INVISIBLE (-3000 1650);
FORCEPROP 1 LAST PATH I241
J 0
(-3327 1775);
DISPLAY 0.872340 (-3327 1775);
PAINT GREEN (-3327 1775);
DISPLAY INVISIBLE (-3327 1775);
FORCEADD TAP..1
(-3325 1725);
FORCEPROP 3 LASTPIN (-3375 1725) SIG_NAME M_D_CPU0_SB_CB<5>
J 0
(-3365 1735);
DISPLAY 0.659574 (-3365 1735);
PAINT MONO (-3365 1735);
DISPLAY INVISIBLE (-3365 1735);
FORCEPROP 1 LASTPIN (-3375 1725) BN 5
J 0
(-3387 1733);
DISPLAY 0.489362 (-3387 1733);
PAINT GREEN (-3387 1733);
FORCEPROP 2 LAST CDS_LIB mstr_standard
J 2
(-3325 1725);
DISPLAY 0.723404 (-3325 1725);
PAINT MONO (-3325 1725);
DISPLAY INVISIBLE (-3325 1725);
FORCEPROP 1 LAST BODY_TYPE PLUMBING
J 0
(-3325 1775);
DISPLAY 0.872340 (-3325 1775);
PAINT GREEN (-3325 1775);
DISPLAY INVISIBLE (-3325 1775);
FORCEPROP 1 LAST HDL_TAP TRUE
J 0
(-3000 1600);
DISPLAY 0.872340 (-3000 1600);
DISPLAY INVISIBLE (-3000 1600);
FORCEPROP 1 LAST PATH I242
J 0
(-3327 1725);
DISPLAY 0.872340 (-3327 1725);
PAINT GREEN (-3327 1725);
DISPLAY INVISIBLE (-3327 1725);
FORCEADD TAP..1
(-3325 1625);
FORCEPROP 3 LASTPIN (-3375 1625) SIG_NAME M_D_CPU0_SB_CB<7>
J 0
(-3365 1635);
DISPLAY 0.659574 (-3365 1635);
PAINT MONO (-3365 1635);
DISPLAY INVISIBLE (-3365 1635);
FORCEPROP 1 LASTPIN (-3375 1625) BN 7
J 0
(-3387 1633);
DISPLAY 0.489362 (-3387 1633);
PAINT GREEN (-3387 1633);
FORCEPROP 2 LAST CDS_LIB mstr_standard
J 2
(-3325 1625);
DISPLAY 0.723404 (-3325 1625);
PAINT MONO (-3325 1625);
DISPLAY INVISIBLE (-3325 1625);
FORCEPROP 1 LAST BODY_TYPE PLUMBING
J 0
(-3325 1675);
DISPLAY 0.872340 (-3325 1675);
PAINT GREEN (-3325 1675);
DISPLAY INVISIBLE (-3325 1675);
FORCEPROP 1 LAST HDL_TAP TRUE
J 0
(-3000 1500);
DISPLAY 0.872340 (-3000 1500);
DISPLAY INVISIBLE (-3000 1500);
FORCEPROP 1 LAST PATH I243
J 0
(-3327 1625);
DISPLAY 0.872340 (-3327 1625);
PAINT GREEN (-3327 1625);
DISPLAY INVISIBLE (-3327 1625);
FORCEADD TAP..1
R 2
(-5750 6025);
FORCEPROP 3 LASTPIN (-5700 6025) SIG_NAME M_D_CPU0_SA_DQS_DP<0>
J 0
(-5690 6035);
DISPLAY 0.659574 (-5690 6035);
PAINT MONO (-5690 6035);
DISPLAY INVISIBLE (-5690 6035);
FORCEPROP 1 LASTPIN (-5700 6025) BN 0
J 2
(-5688 6033);
DISPLAY 0.489362 (-5688 6033);
PAINT GREEN (-5688 6033);
FORCEPROP 2 LAST CDS_LIB mstr_standard
J 2
(-5750 6025);
DISPLAY 0.723404 (-5750 6025);
PAINT MONO (-5750 6025);
DISPLAY INVISIBLE (-5750 6025);
FORCEPROP 1 LAST BODY_TYPE PLUMBING
J 2
(-5750 6075);
DISPLAY 0.872340 (-5750 6075);
PAINT GREEN (-5750 6075);
DISPLAY INVISIBLE (-5750 6075);
FORCEPROP 1 LAST HDL_TAP TRUE
J 2
(-6075 5900);
DISPLAY 0.872340 (-6075 5900);
DISPLAY INVISIBLE (-6075 5900);
FORCEPROP 1 LAST PATH I244
J 2
(-5748 6025);
DISPLAY 0.872340 (-5748 6025);
PAINT GREEN (-5748 6025);
DISPLAY INVISIBLE (-5748 6025);
FORCEADD TAP..1
R 2
(-5750 5925);
FORCEPROP 3 LASTPIN (-5700 5925) SIG_NAME M_D_CPU0_SA_DQS_DP<1>
J 0
(-5690 5935);
DISPLAY 0.659574 (-5690 5935);
PAINT MONO (-5690 5935);
DISPLAY INVISIBLE (-5690 5935);
FORCEPROP 1 LASTPIN (-5700 5925) BN 1
J 2
(-5688 5933);
DISPLAY 0.489362 (-5688 5933);
PAINT GREEN (-5688 5933);
FORCEPROP 2 LAST CDS_LIB mstr_standard
J 2
(-5750 5925);
DISPLAY 0.723404 (-5750 5925);
PAINT MONO (-5750 5925);
DISPLAY INVISIBLE (-5750 5925);
FORCEPROP 1 LAST BODY_TYPE PLUMBING
J 2
(-5750 5975);
DISPLAY 0.872340 (-5750 5975);
PAINT GREEN (-5750 5975);
DISPLAY INVISIBLE (-5750 5975);
FORCEPROP 1 LAST HDL_TAP TRUE
J 2
(-6075 5800);
DISPLAY 0.872340 (-6075 5800);
DISPLAY INVISIBLE (-6075 5800);
FORCEPROP 1 LAST PATH I245
J 2
(-5748 5925);
DISPLAY 0.872340 (-5748 5925);
PAINT GREEN (-5748 5925);
DISPLAY INVISIBLE (-5748 5925);
FORCEADD TAP..1
R 2
(-5750 5825);
FORCEPROP 3 LASTPIN (-5700 5825) SIG_NAME M_D_CPU0_SA_DQS_DP<2>
J 0
(-5690 5835);
DISPLAY 0.659574 (-5690 5835);
PAINT MONO (-5690 5835);
DISPLAY INVISIBLE (-5690 5835);
FORCEPROP 1 LASTPIN (-5700 5825) BN 2
J 2
(-5688 5833);
DISPLAY 0.489362 (-5688 5833);
PAINT GREEN (-5688 5833);
FORCEPROP 2 LAST CDS_LIB mstr_standard
J 2
(-5750 5825);
DISPLAY 0.723404 (-5750 5825);
PAINT MONO (-5750 5825);
DISPLAY INVISIBLE (-5750 5825);
FORCEPROP 1 LAST BODY_TYPE PLUMBING
J 2
(-5750 5875);
DISPLAY 0.872340 (-5750 5875);
PAINT GREEN (-5750 5875);
DISPLAY INVISIBLE (-5750 5875);
FORCEPROP 1 LAST HDL_TAP TRUE
J 2
(-6075 5700);
DISPLAY 0.872340 (-6075 5700);
DISPLAY INVISIBLE (-6075 5700);
FORCEPROP 1 LAST PATH I246
J 2
(-5748 5825);
DISPLAY 0.872340 (-5748 5825);
PAINT GREEN (-5748 5825);
DISPLAY INVISIBLE (-5748 5825);
FORCEADD TAP..1
R 2
(-5750 5725);
FORCEPROP 3 LASTPIN (-5700 5725) SIG_NAME M_D_CPU0_SA_DQS_DP<3>
J 0
(-5690 5735);
DISPLAY 0.659574 (-5690 5735);
PAINT MONO (-5690 5735);
DISPLAY INVISIBLE (-5690 5735);
FORCEPROP 1 LASTPIN (-5700 5725) BN 3
J 2
(-5688 5733);
DISPLAY 0.489362 (-5688 5733);
PAINT GREEN (-5688 5733);
FORCEPROP 2 LAST CDS_LIB mstr_standard
J 2
(-5750 5725);
DISPLAY 0.723404 (-5750 5725);
PAINT MONO (-5750 5725);
DISPLAY INVISIBLE (-5750 5725);
FORCEPROP 1 LAST BODY_TYPE PLUMBING
J 2
(-5750 5775);
DISPLAY 0.872340 (-5750 5775);
PAINT GREEN (-5750 5775);
DISPLAY INVISIBLE (-5750 5775);
FORCEPROP 1 LAST HDL_TAP TRUE
J 2
(-6075 5600);
DISPLAY 0.872340 (-6075 5600);
DISPLAY INVISIBLE (-6075 5600);
FORCEPROP 1 LAST PATH I247
J 2
(-5748 5725);
DISPLAY 0.872340 (-5748 5725);
PAINT GREEN (-5748 5725);
DISPLAY INVISIBLE (-5748 5725);
FORCEADD TAP..1
R 2
(-5950 5975);
FORCEPROP 3 LASTPIN (-5900 5975) SIG_NAME M_D_CPU0_SA_DQS_DN<0>
J 0
(-5890 5985);
DISPLAY 0.659574 (-5890 5985);
PAINT MONO (-5890 5985);
DISPLAY INVISIBLE (-5890 5985);
FORCEPROP 1 LASTPIN (-5900 5975) BN 0
J 2
(-5888 5983);
DISPLAY 0.489362 (-5888 5983);
PAINT GREEN (-5888 5983);
FORCEPROP 2 LAST CDS_LIB mstr_standard
J 2
(-5950 5975);
DISPLAY 0.723404 (-5950 5975);
PAINT MONO (-5950 5975);
DISPLAY INVISIBLE (-5950 5975);
FORCEPROP 1 LAST BODY_TYPE PLUMBING
J 2
(-5950 6025);
DISPLAY 0.872340 (-5950 6025);
PAINT GREEN (-5950 6025);
DISPLAY INVISIBLE (-5950 6025);
FORCEPROP 1 LAST HDL_TAP TRUE
J 2
(-6275 5850);
DISPLAY 0.872340 (-6275 5850);
DISPLAY INVISIBLE (-6275 5850);
FORCEPROP 1 LAST PATH I248
J 2
(-5948 5975);
DISPLAY 0.872340 (-5948 5975);
PAINT GREEN (-5948 5975);
DISPLAY INVISIBLE (-5948 5975);
FORCEADD TAP..1
R 2
(-5950 5875);
FORCEPROP 3 LASTPIN (-5900 5875) SIG_NAME M_D_CPU0_SA_DQS_DN<1>
J 0
(-5890 5885);
DISPLAY 0.659574 (-5890 5885);
PAINT MONO (-5890 5885);
DISPLAY INVISIBLE (-5890 5885);
FORCEPROP 1 LASTPIN (-5900 5875) BN 1
J 2
(-5888 5883);
DISPLAY 0.489362 (-5888 5883);
PAINT GREEN (-5888 5883);
FORCEPROP 2 LAST CDS_LIB mstr_standard
J 2
(-5950 5875);
DISPLAY 0.723404 (-5950 5875);
PAINT MONO (-5950 5875);
DISPLAY INVISIBLE (-5950 5875);
FORCEPROP 1 LAST BODY_TYPE PLUMBING
J 2
(-5950 5925);
DISPLAY 0.872340 (-5950 5925);
PAINT GREEN (-5950 5925);
DISPLAY INVISIBLE (-5950 5925);
FORCEPROP 1 LAST HDL_TAP TRUE
J 2
(-6275 5750);
DISPLAY 0.872340 (-6275 5750);
DISPLAY INVISIBLE (-6275 5750);
FORCEPROP 1 LAST PATH I249
J 2
(-5948 5875);
DISPLAY 0.872340 (-5948 5875);
PAINT GREEN (-5948 5875);
DISPLAY INVISIBLE (-5948 5875);
FORCEADD TAP..1
R 2
(-5950 5775);
FORCEPROP 3 LASTPIN (-5900 5775) SIG_NAME M_D_CPU0_SA_DQS_DN<2>
J 0
(-5890 5785);
DISPLAY 0.659574 (-5890 5785);
PAINT MONO (-5890 5785);
DISPLAY INVISIBLE (-5890 5785);
FORCEPROP 1 LASTPIN (-5900 5775) BN 2
J 2
(-5888 5783);
DISPLAY 0.489362 (-5888 5783);
PAINT GREEN (-5888 5783);
FORCEPROP 2 LAST CDS_LIB mstr_standard
J 2
(-5950 5775);
DISPLAY 0.723404 (-5950 5775);
PAINT MONO (-5950 5775);
DISPLAY INVISIBLE (-5950 5775);
FORCEPROP 1 LAST BODY_TYPE PLUMBING
J 2
(-5950 5825);
DISPLAY 0.872340 (-5950 5825);
PAINT GREEN (-5950 5825);
DISPLAY INVISIBLE (-5950 5825);
FORCEPROP 1 LAST HDL_TAP TRUE
J 2
(-6275 5650);
DISPLAY 0.872340 (-6275 5650);
DISPLAY INVISIBLE (-6275 5650);
FORCEPROP 1 LAST PATH I250
J 2
(-5948 5775);
DISPLAY 0.872340 (-5948 5775);
PAINT GREEN (-5948 5775);
DISPLAY INVISIBLE (-5948 5775);
FORCEADD TAP..1
R 2
(-5950 5675);
FORCEPROP 3 LASTPIN (-5900 5675) SIG_NAME M_D_CPU0_SA_DQS_DN<3>
J 0
(-5890 5685);
DISPLAY 0.659574 (-5890 5685);
PAINT MONO (-5890 5685);
DISPLAY INVISIBLE (-5890 5685);
FORCEPROP 1 LASTPIN (-5900 5675) BN 3
J 2
(-5888 5683);
DISPLAY 0.489362 (-5888 5683);
PAINT GREEN (-5888 5683);
FORCEPROP 2 LAST CDS_LIB mstr_standard
J 2
(-5950 5675);
DISPLAY 0.723404 (-5950 5675);
PAINT MONO (-5950 5675);
DISPLAY INVISIBLE (-5950 5675);
FORCEPROP 1 LAST BODY_TYPE PLUMBING
J 2
(-5950 5725);
DISPLAY 0.872340 (-5950 5725);
PAINT GREEN (-5950 5725);
DISPLAY INVISIBLE (-5950 5725);
FORCEPROP 1 LAST HDL_TAP TRUE
J 2
(-6275 5550);
DISPLAY 0.872340 (-6275 5550);
DISPLAY INVISIBLE (-6275 5550);
FORCEPROP 1 LAST PATH I251
J 2
(-5948 5675);
DISPLAY 0.872340 (-5948 5675);
PAINT GREEN (-5948 5675);
DISPLAY INVISIBLE (-5948 5675);
FORCEADD TAP..1
R 2
(-5750 5525);
FORCEPROP 3 LASTPIN (-5700 5525) SIG_NAME M_D_CPU0_SA_DQS_DP<5>
J 0
(-5690 5535);
DISPLAY 0.659574 (-5690 5535);
PAINT MONO (-5690 5535);
DISPLAY INVISIBLE (-5690 5535);
FORCEPROP 1 LASTPIN (-5700 5525) BN 5
J 2
(-5688 5533);
DISPLAY 0.489362 (-5688 5533);
PAINT GREEN (-5688 5533);
FORCEPROP 2 LAST CDS_LIB mstr_standard
J 2
(-5750 5525);
DISPLAY 0.723404 (-5750 5525);
PAINT MONO (-5750 5525);
DISPLAY INVISIBLE (-5750 5525);
FORCEPROP 1 LAST BODY_TYPE PLUMBING
J 2
(-5750 5575);
DISPLAY 0.872340 (-5750 5575);
PAINT GREEN (-5750 5575);
DISPLAY INVISIBLE (-5750 5575);
FORCEPROP 1 LAST HDL_TAP TRUE
J 2
(-6075 5400);
DISPLAY 0.872340 (-6075 5400);
DISPLAY INVISIBLE (-6075 5400);
FORCEPROP 1 LAST PATH I252
J 2
(-5748 5525);
DISPLAY 0.872340 (-5748 5525);
PAINT GREEN (-5748 5525);
DISPLAY INVISIBLE (-5748 5525);
FORCEADD TAP..1
R 2
(-5750 5625);
FORCEPROP 3 LASTPIN (-5700 5625) SIG_NAME M_D_CPU0_SA_DQS_DP<4>
J 0
(-5690 5635);
DISPLAY 0.659574 (-5690 5635);
PAINT MONO (-5690 5635);
DISPLAY INVISIBLE (-5690 5635);
FORCEPROP 1 LASTPIN (-5700 5625) BN 4
J 2
(-5688 5633);
DISPLAY 0.489362 (-5688 5633);
PAINT GREEN (-5688 5633);
FORCEPROP 2 LAST CDS_LIB mstr_standard
J 2
(-5750 5625);
DISPLAY 0.723404 (-5750 5625);
PAINT MONO (-5750 5625);
DISPLAY INVISIBLE (-5750 5625);
FORCEPROP 1 LAST BODY_TYPE PLUMBING
J 2
(-5750 5675);
DISPLAY 0.872340 (-5750 5675);
PAINT GREEN (-5750 5675);
DISPLAY INVISIBLE (-5750 5675);
FORCEPROP 1 LAST HDL_TAP TRUE
J 2
(-6075 5500);
DISPLAY 0.872340 (-6075 5500);
DISPLAY INVISIBLE (-6075 5500);
FORCEPROP 1 LAST PATH I253
J 2
(-5748 5625);
DISPLAY 0.872340 (-5748 5625);
PAINT GREEN (-5748 5625);
DISPLAY INVISIBLE (-5748 5625);
FORCEADD TAP..1
R 2
(-5750 5425);
FORCEPROP 3 LASTPIN (-5700 5425) SIG_NAME M_D_CPU0_SA_DQS_DP<6>
J 0
(-5690 5435);
DISPLAY 0.659574 (-5690 5435);
PAINT MONO (-5690 5435);
DISPLAY INVISIBLE (-5690 5435);
FORCEPROP 1 LASTPIN (-5700 5425) BN 6
J 2
(-5688 5433);
DISPLAY 0.489362 (-5688 5433);
PAINT GREEN (-5688 5433);
FORCEPROP 2 LAST CDS_LIB mstr_standard
J 2
(-5750 5425);
DISPLAY 0.723404 (-5750 5425);
PAINT MONO (-5750 5425);
DISPLAY INVISIBLE (-5750 5425);
FORCEPROP 1 LAST BODY_TYPE PLUMBING
J 2
(-5750 5475);
DISPLAY 0.872340 (-5750 5475);
PAINT GREEN (-5750 5475);
DISPLAY INVISIBLE (-5750 5475);
FORCEPROP 1 LAST HDL_TAP TRUE
J 2
(-6075 5300);
DISPLAY 0.872340 (-6075 5300);
DISPLAY INVISIBLE (-6075 5300);
FORCEPROP 1 LAST PATH I254
J 2
(-5748 5425);
DISPLAY 0.872340 (-5748 5425);
PAINT GREEN (-5748 5425);
DISPLAY INVISIBLE (-5748 5425);
FORCEADD TAP..1
R 2
(-5750 5325);
FORCEPROP 3 LASTPIN (-5700 5325) SIG_NAME M_D_CPU0_SA_DQS_DP<7>
J 0
(-5690 5335);
DISPLAY 0.659574 (-5690 5335);
PAINT MONO (-5690 5335);
DISPLAY INVISIBLE (-5690 5335);
FORCEPROP 1 LASTPIN (-5700 5325) BN 7
J 2
(-5688 5333);
DISPLAY 0.489362 (-5688 5333);
PAINT GREEN (-5688 5333);
FORCEPROP 2 LAST CDS_LIB mstr_standard
J 2
(-5750 5325);
DISPLAY 0.723404 (-5750 5325);
PAINT MONO (-5750 5325);
DISPLAY INVISIBLE (-5750 5325);
FORCEPROP 1 LAST BODY_TYPE PLUMBING
J 2
(-5750 5375);
DISPLAY 0.872340 (-5750 5375);
PAINT GREEN (-5750 5375);
DISPLAY INVISIBLE (-5750 5375);
FORCEPROP 1 LAST HDL_TAP TRUE
J 2
(-6075 5200);
DISPLAY 0.872340 (-6075 5200);
DISPLAY INVISIBLE (-6075 5200);
FORCEPROP 1 LAST PATH I255
J 2
(-5748 5325);
DISPLAY 0.872340 (-5748 5325);
PAINT GREEN (-5748 5325);
DISPLAY INVISIBLE (-5748 5325);
FORCEADD TAP..1
R 2
(-5750 5125);
FORCEPROP 3 LASTPIN (-5700 5125) SIG_NAME M_D_CPU0_SA_DQS_DP<9>
J 0
(-5690 5135);
DISPLAY 0.659574 (-5690 5135);
PAINT MONO (-5690 5135);
DISPLAY INVISIBLE (-5690 5135);
FORCEPROP 1 LASTPIN (-5700 5125) BN 9
J 2
(-5688 5133);
DISPLAY 0.489362 (-5688 5133);
PAINT GREEN (-5688 5133);
FORCEPROP 2 LAST CDS_LIB mstr_standard
J 2
(-5750 5125);
DISPLAY 0.723404 (-5750 5125);
PAINT MONO (-5750 5125);
DISPLAY INVISIBLE (-5750 5125);
FORCEPROP 1 LAST BODY_TYPE PLUMBING
J 2
(-5750 5175);
DISPLAY 0.872340 (-5750 5175);
PAINT GREEN (-5750 5175);
DISPLAY INVISIBLE (-5750 5175);
FORCEPROP 1 LAST HDL_TAP TRUE
J 2
(-6075 5000);
DISPLAY 0.872340 (-6075 5000);
DISPLAY INVISIBLE (-6075 5000);
FORCEPROP 1 LAST PATH I256
J 2
(-5748 5125);
DISPLAY 0.872340 (-5748 5125);
PAINT GREEN (-5748 5125);
DISPLAY INVISIBLE (-5748 5125);
FORCEADD TAP..1
R 2
(-5750 5225);
FORCEPROP 3 LASTPIN (-5700 5225) SIG_NAME M_D_CPU0_SA_DQS_DP<8>
J 0
(-5690 5235);
DISPLAY 0.659574 (-5690 5235);
PAINT MONO (-5690 5235);
DISPLAY INVISIBLE (-5690 5235);
FORCEPROP 1 LASTPIN (-5700 5225) BN 8
J 2
(-5688 5233);
DISPLAY 0.489362 (-5688 5233);
PAINT GREEN (-5688 5233);
FORCEPROP 2 LAST CDS_LIB mstr_standard
J 2
(-5750 5225);
DISPLAY 0.723404 (-5750 5225);
PAINT MONO (-5750 5225);
DISPLAY INVISIBLE (-5750 5225);
FORCEPROP 1 LAST BODY_TYPE PLUMBING
J 2
(-5750 5275);
DISPLAY 0.872340 (-5750 5275);
PAINT GREEN (-5750 5275);
DISPLAY INVISIBLE (-5750 5275);
FORCEPROP 1 LAST HDL_TAP TRUE
J 2
(-6075 5100);
DISPLAY 0.872340 (-6075 5100);
DISPLAY INVISIBLE (-6075 5100);
FORCEPROP 1 LAST PATH I257
J 2
(-5748 5225);
DISPLAY 0.872340 (-5748 5225);
PAINT GREEN (-5748 5225);
DISPLAY INVISIBLE (-5748 5225);
FORCEADD TAP..1
R 2
(-5950 5575);
FORCEPROP 3 LASTPIN (-5900 5575) SIG_NAME M_D_CPU0_SA_DQS_DN<4>
J 0
(-5890 5585);
DISPLAY 0.659574 (-5890 5585);
PAINT MONO (-5890 5585);
DISPLAY INVISIBLE (-5890 5585);
FORCEPROP 1 LASTPIN (-5900 5575) BN 4
J 2
(-5888 5583);
DISPLAY 0.489362 (-5888 5583);
PAINT GREEN (-5888 5583);
FORCEPROP 2 LAST CDS_LIB mstr_standard
J 2
(-5950 5575);
DISPLAY 0.723404 (-5950 5575);
PAINT MONO (-5950 5575);
DISPLAY INVISIBLE (-5950 5575);
FORCEPROP 1 LAST BODY_TYPE PLUMBING
J 2
(-5950 5625);
DISPLAY 0.872340 (-5950 5625);
PAINT GREEN (-5950 5625);
DISPLAY INVISIBLE (-5950 5625);
FORCEPROP 1 LAST HDL_TAP TRUE
J 2
(-6275 5450);
DISPLAY 0.872340 (-6275 5450);
DISPLAY INVISIBLE (-6275 5450);
FORCEPROP 1 LAST PATH I258
J 2
(-5948 5575);
DISPLAY 0.872340 (-5948 5575);
PAINT GREEN (-5948 5575);
DISPLAY INVISIBLE (-5948 5575);
FORCEADD TAP..1
R 2
(-5950 5475);
FORCEPROP 3 LASTPIN (-5900 5475) SIG_NAME M_D_CPU0_SA_DQS_DN<5>
J 0
(-5890 5485);
DISPLAY 0.659574 (-5890 5485);
PAINT MONO (-5890 5485);
DISPLAY INVISIBLE (-5890 5485);
FORCEPROP 1 LASTPIN (-5900 5475) BN 5
J 2
(-5888 5483);
DISPLAY 0.489362 (-5888 5483);
PAINT GREEN (-5888 5483);
FORCEPROP 2 LAST CDS_LIB mstr_standard
J 2
(-5950 5475);
DISPLAY 0.723404 (-5950 5475);
PAINT MONO (-5950 5475);
DISPLAY INVISIBLE (-5950 5475);
FORCEPROP 1 LAST BODY_TYPE PLUMBING
J 2
(-5950 5525);
DISPLAY 0.872340 (-5950 5525);
PAINT GREEN (-5950 5525);
DISPLAY INVISIBLE (-5950 5525);
FORCEPROP 1 LAST HDL_TAP TRUE
J 2
(-6275 5350);
DISPLAY 0.872340 (-6275 5350);
DISPLAY INVISIBLE (-6275 5350);
FORCEPROP 1 LAST PATH I259
J 2
(-5948 5475);
DISPLAY 0.872340 (-5948 5475);
PAINT GREEN (-5948 5475);
DISPLAY INVISIBLE (-5948 5475);
FORCEADD TAP..1
R 2
(-5950 5375);
FORCEPROP 3 LASTPIN (-5900 5375) SIG_NAME M_D_CPU0_SA_DQS_DN<6>
J 0
(-5890 5385);
DISPLAY 0.659574 (-5890 5385);
PAINT MONO (-5890 5385);
DISPLAY INVISIBLE (-5890 5385);
FORCEPROP 1 LASTPIN (-5900 5375) BN 6
J 2
(-5888 5383);
DISPLAY 0.489362 (-5888 5383);
PAINT GREEN (-5888 5383);
FORCEPROP 2 LAST CDS_LIB mstr_standard
J 2
(-5950 5375);
DISPLAY 0.723404 (-5950 5375);
PAINT MONO (-5950 5375);
DISPLAY INVISIBLE (-5950 5375);
FORCEPROP 1 LAST BODY_TYPE PLUMBING
J 2
(-5950 5425);
DISPLAY 0.872340 (-5950 5425);
PAINT GREEN (-5950 5425);
DISPLAY INVISIBLE (-5950 5425);
FORCEPROP 1 LAST HDL_TAP TRUE
J 2
(-6275 5250);
DISPLAY 0.872340 (-6275 5250);
DISPLAY INVISIBLE (-6275 5250);
FORCEPROP 1 LAST PATH I260
J 2
(-5948 5375);
DISPLAY 0.872340 (-5948 5375);
PAINT GREEN (-5948 5375);
DISPLAY INVISIBLE (-5948 5375);
FORCEADD TAP..1
R 2
(-5950 5275);
FORCEPROP 3 LASTPIN (-5900 5275) SIG_NAME M_D_CPU0_SA_DQS_DN<7>
J 0
(-5890 5285);
DISPLAY 0.659574 (-5890 5285);
PAINT MONO (-5890 5285);
DISPLAY INVISIBLE (-5890 5285);
FORCEPROP 1 LASTPIN (-5900 5275) BN 7
J 2
(-5888 5283);
DISPLAY 0.489362 (-5888 5283);
PAINT GREEN (-5888 5283);
FORCEPROP 2 LAST CDS_LIB mstr_standard
J 2
(-5950 5275);
DISPLAY 0.723404 (-5950 5275);
PAINT MONO (-5950 5275);
DISPLAY INVISIBLE (-5950 5275);
FORCEPROP 1 LAST BODY_TYPE PLUMBING
J 2
(-5950 5325);
DISPLAY 0.872340 (-5950 5325);
PAINT GREEN (-5950 5325);
DISPLAY INVISIBLE (-5950 5325);
FORCEPROP 1 LAST HDL_TAP TRUE
J 2
(-6275 5150);
DISPLAY 0.872340 (-6275 5150);
DISPLAY INVISIBLE (-6275 5150);
FORCEPROP 1 LAST PATH I261
J 2
(-5948 5275);
DISPLAY 0.872340 (-5948 5275);
PAINT GREEN (-5948 5275);
DISPLAY INVISIBLE (-5948 5275);
FORCEADD TAP..1
R 2
(-5950 5175);
FORCEPROP 3 LASTPIN (-5900 5175) SIG_NAME M_D_CPU0_SA_DQS_DN<8>
J 0
(-5890 5185);
DISPLAY 0.659574 (-5890 5185);
PAINT MONO (-5890 5185);
DISPLAY INVISIBLE (-5890 5185);
FORCEPROP 1 LASTPIN (-5900 5175) BN 8
J 2
(-5888 5183);
DISPLAY 0.489362 (-5888 5183);
PAINT GREEN (-5888 5183);
FORCEPROP 2 LAST CDS_LIB mstr_standard
J 2
(-5950 5175);
DISPLAY 0.723404 (-5950 5175);
PAINT MONO (-5950 5175);
DISPLAY INVISIBLE (-5950 5175);
FORCEPROP 1 LAST BODY_TYPE PLUMBING
J 2
(-5950 5225);
DISPLAY 0.872340 (-5950 5225);
PAINT GREEN (-5950 5225);
DISPLAY INVISIBLE (-5950 5225);
FORCEPROP 1 LAST HDL_TAP TRUE
J 2
(-6275 5050);
DISPLAY 0.872340 (-6275 5050);
DISPLAY INVISIBLE (-6275 5050);
FORCEPROP 1 LAST PATH I262
J 2
(-5948 5175);
DISPLAY 0.872340 (-5948 5175);
PAINT GREEN (-5948 5175);
DISPLAY INVISIBLE (-5948 5175);
FORCEADD TAP..1
R 2
(-5750 4875);
FORCEPROP 3 LASTPIN (-5700 4875) SIG_NAME M_D_CPU0_SB_DQS_DP<1>
J 0
(-5690 4885);
DISPLAY 0.659574 (-5690 4885);
PAINT MONO (-5690 4885);
DISPLAY INVISIBLE (-5690 4885);
FORCEPROP 1 LASTPIN (-5700 4875) BN 1
J 2
(-5688 4883);
DISPLAY 0.489362 (-5688 4883);
PAINT GREEN (-5688 4883);
FORCEPROP 2 LAST CDS_LIB mstr_standard
J 2
(-5750 4875);
DISPLAY 0.723404 (-5750 4875);
PAINT MONO (-5750 4875);
DISPLAY INVISIBLE (-5750 4875);
FORCEPROP 1 LAST BODY_TYPE PLUMBING
J 2
(-5750 4925);
DISPLAY 0.872340 (-5750 4925);
PAINT GREEN (-5750 4925);
DISPLAY INVISIBLE (-5750 4925);
FORCEPROP 1 LAST HDL_TAP TRUE
J 2
(-6075 4750);
DISPLAY 0.872340 (-6075 4750);
DISPLAY INVISIBLE (-6075 4750);
FORCEPROP 1 LAST PATH I263
J 2
(-5748 4875);
DISPLAY 0.872340 (-5748 4875);
PAINT GREEN (-5748 4875);
DISPLAY INVISIBLE (-5748 4875);
FORCEADD TAP..1
R 2
(-5750 4975);
FORCEPROP 3 LASTPIN (-5700 4975) SIG_NAME M_D_CPU0_SB_DQS_DP<0>
J 0
(-5690 4985);
DISPLAY 0.659574 (-5690 4985);
PAINT MONO (-5690 4985);
DISPLAY INVISIBLE (-5690 4985);
FORCEPROP 1 LASTPIN (-5700 4975) BN 0
J 2
(-5688 4983);
DISPLAY 0.489362 (-5688 4983);
PAINT GREEN (-5688 4983);
FORCEPROP 2 LAST CDS_LIB mstr_standard
J 2
(-5750 4975);
DISPLAY 0.723404 (-5750 4975);
PAINT MONO (-5750 4975);
DISPLAY INVISIBLE (-5750 4975);
FORCEPROP 1 LAST BODY_TYPE PLUMBING
J 2
(-5750 5025);
DISPLAY 0.872340 (-5750 5025);
PAINT GREEN (-5750 5025);
DISPLAY INVISIBLE (-5750 5025);
FORCEPROP 1 LAST HDL_TAP TRUE
J 2
(-6075 4850);
DISPLAY 0.872340 (-6075 4850);
DISPLAY INVISIBLE (-6075 4850);
FORCEPROP 1 LAST PATH I264
J 2
(-5748 4975);
DISPLAY 0.872340 (-5748 4975);
PAINT GREEN (-5748 4975);
DISPLAY INVISIBLE (-5748 4975);
FORCEADD TAP..1
R 2
(-5750 4775);
FORCEPROP 3 LASTPIN (-5700 4775) SIG_NAME M_D_CPU0_SB_DQS_DP<2>
J 0
(-5690 4785);
DISPLAY 0.659574 (-5690 4785);
PAINT MONO (-5690 4785);
DISPLAY INVISIBLE (-5690 4785);
FORCEPROP 1 LASTPIN (-5700 4775) BN 2
J 2
(-5688 4783);
DISPLAY 0.489362 (-5688 4783);
PAINT GREEN (-5688 4783);
FORCEPROP 2 LAST CDS_LIB mstr_standard
J 2
(-5750 4775);
DISPLAY 0.723404 (-5750 4775);
PAINT MONO (-5750 4775);
DISPLAY INVISIBLE (-5750 4775);
FORCEPROP 1 LAST BODY_TYPE PLUMBING
J 2
(-5750 4825);
DISPLAY 0.872340 (-5750 4825);
PAINT GREEN (-5750 4825);
DISPLAY INVISIBLE (-5750 4825);
FORCEPROP 1 LAST HDL_TAP TRUE
J 2
(-6075 4650);
DISPLAY 0.872340 (-6075 4650);
DISPLAY INVISIBLE (-6075 4650);
FORCEPROP 1 LAST PATH I265
J 2
(-5748 4775);
DISPLAY 0.872340 (-5748 4775);
PAINT GREEN (-5748 4775);
DISPLAY INVISIBLE (-5748 4775);
FORCEADD TAP..1
R 2
(-5750 4675);
FORCEPROP 3 LASTPIN (-5700 4675) SIG_NAME M_D_CPU0_SB_DQS_DP<3>
J 0
(-5690 4685);
DISPLAY 0.659574 (-5690 4685);
PAINT MONO (-5690 4685);
DISPLAY INVISIBLE (-5690 4685);
FORCEPROP 1 LASTPIN (-5700 4675) BN 3
J 2
(-5688 4683);
DISPLAY 0.489362 (-5688 4683);
PAINT GREEN (-5688 4683);
FORCEPROP 2 LAST CDS_LIB mstr_standard
J 2
(-5750 4675);
DISPLAY 0.723404 (-5750 4675);
PAINT MONO (-5750 4675);
DISPLAY INVISIBLE (-5750 4675);
FORCEPROP 1 LAST BODY_TYPE PLUMBING
J 2
(-5750 4725);
DISPLAY 0.872340 (-5750 4725);
PAINT GREEN (-5750 4725);
DISPLAY INVISIBLE (-5750 4725);
FORCEPROP 1 LAST HDL_TAP TRUE
J 2
(-6075 4550);
DISPLAY 0.872340 (-6075 4550);
DISPLAY INVISIBLE (-6075 4550);
FORCEPROP 1 LAST PATH I266
J 2
(-5748 4675);
DISPLAY 0.872340 (-5748 4675);
PAINT GREEN (-5748 4675);
DISPLAY INVISIBLE (-5748 4675);
FORCEADD TAP..1
R 2
(-5950 5075);
FORCEPROP 3 LASTPIN (-5900 5075) SIG_NAME M_D_CPU0_SA_DQS_DN<9>
J 0
(-5890 5085);
DISPLAY 0.659574 (-5890 5085);
PAINT MONO (-5890 5085);
DISPLAY INVISIBLE (-5890 5085);
FORCEPROP 1 LASTPIN (-5900 5075) BN 9
J 2
(-5888 5083);
DISPLAY 0.489362 (-5888 5083);
PAINT GREEN (-5888 5083);
FORCEPROP 2 LAST CDS_LIB mstr_standard
J 2
(-5950 5075);
DISPLAY 0.723404 (-5950 5075);
PAINT MONO (-5950 5075);
DISPLAY INVISIBLE (-5950 5075);
FORCEPROP 1 LAST BODY_TYPE PLUMBING
J 2
(-5950 5125);
DISPLAY 0.872340 (-5950 5125);
PAINT GREEN (-5950 5125);
DISPLAY INVISIBLE (-5950 5125);
FORCEPROP 1 LAST HDL_TAP TRUE
J 2
(-6275 4950);
DISPLAY 0.872340 (-6275 4950);
DISPLAY INVISIBLE (-6275 4950);
FORCEPROP 1 LAST PATH I267
J 2
(-5948 5075);
DISPLAY 0.872340 (-5948 5075);
PAINT GREEN (-5948 5075);
DISPLAY INVISIBLE (-5948 5075);
FORCEADD TAP..1
R 2
(-5950 4925);
FORCEPROP 3 LASTPIN (-5900 4925) SIG_NAME M_D_CPU0_SB_DQS_DN<0>
J 0
(-5890 4935);
DISPLAY 0.659574 (-5890 4935);
PAINT MONO (-5890 4935);
DISPLAY INVISIBLE (-5890 4935);
FORCEPROP 1 LASTPIN (-5900 4925) BN 0
J 2
(-5888 4933);
DISPLAY 0.489362 (-5888 4933);
PAINT GREEN (-5888 4933);
FORCEPROP 2 LAST CDS_LIB mstr_standard
J 2
(-5950 4925);
DISPLAY 0.723404 (-5950 4925);
PAINT MONO (-5950 4925);
DISPLAY INVISIBLE (-5950 4925);
FORCEPROP 1 LAST BODY_TYPE PLUMBING
J 2
(-5950 4975);
DISPLAY 0.872340 (-5950 4975);
PAINT GREEN (-5950 4975);
DISPLAY INVISIBLE (-5950 4975);
FORCEPROP 1 LAST HDL_TAP TRUE
J 2
(-6275 4800);
DISPLAY 0.872340 (-6275 4800);
DISPLAY INVISIBLE (-6275 4800);
FORCEPROP 1 LAST PATH I268
J 2
(-5948 4925);
DISPLAY 0.872340 (-5948 4925);
PAINT GREEN (-5948 4925);
DISPLAY INVISIBLE (-5948 4925);
FORCEADD TAP..1
R 2
(-5950 4825);
FORCEPROP 3 LASTPIN (-5900 4825) SIG_NAME M_D_CPU0_SB_DQS_DN<1>
J 0
(-5890 4835);
DISPLAY 0.659574 (-5890 4835);
PAINT MONO (-5890 4835);
DISPLAY INVISIBLE (-5890 4835);
FORCEPROP 1 LASTPIN (-5900 4825) BN 1
J 2
(-5888 4833);
DISPLAY 0.489362 (-5888 4833);
PAINT GREEN (-5888 4833);
FORCEPROP 2 LAST CDS_LIB mstr_standard
J 2
(-5950 4825);
DISPLAY 0.723404 (-5950 4825);
PAINT MONO (-5950 4825);
DISPLAY INVISIBLE (-5950 4825);
FORCEPROP 1 LAST BODY_TYPE PLUMBING
J 2
(-5950 4875);
DISPLAY 0.872340 (-5950 4875);
PAINT GREEN (-5950 4875);
DISPLAY INVISIBLE (-5950 4875);
FORCEPROP 1 LAST HDL_TAP TRUE
J 2
(-6275 4700);
DISPLAY 0.872340 (-6275 4700);
DISPLAY INVISIBLE (-6275 4700);
FORCEPROP 1 LAST PATH I269
J 2
(-5948 4825);
DISPLAY 0.872340 (-5948 4825);
PAINT GREEN (-5948 4825);
DISPLAY INVISIBLE (-5948 4825);
FORCEADD TAP..1
R 2
(-5950 4725);
FORCEPROP 3 LASTPIN (-5900 4725) SIG_NAME M_D_CPU0_SB_DQS_DN<2>
J 0
(-5890 4735);
DISPLAY 0.659574 (-5890 4735);
PAINT MONO (-5890 4735);
DISPLAY INVISIBLE (-5890 4735);
FORCEPROP 1 LASTPIN (-5900 4725) BN 2
J 2
(-5888 4733);
DISPLAY 0.489362 (-5888 4733);
PAINT GREEN (-5888 4733);
FORCEPROP 2 LAST CDS_LIB mstr_standard
J 2
(-5950 4725);
DISPLAY 0.723404 (-5950 4725);
PAINT MONO (-5950 4725);
DISPLAY INVISIBLE (-5950 4725);
FORCEPROP 1 LAST BODY_TYPE PLUMBING
J 2
(-5950 4775);
DISPLAY 0.872340 (-5950 4775);
PAINT GREEN (-5950 4775);
DISPLAY INVISIBLE (-5950 4775);
FORCEPROP 1 LAST HDL_TAP TRUE
J 2
(-6275 4600);
DISPLAY 0.872340 (-6275 4600);
DISPLAY INVISIBLE (-6275 4600);
FORCEPROP 1 LAST PATH I270
J 2
(-5948 4725);
DISPLAY 0.872340 (-5948 4725);
PAINT GREEN (-5948 4725);
DISPLAY INVISIBLE (-5948 4725);
FORCEADD TAP..1
R 2
(-5950 4625);
FORCEPROP 3 LASTPIN (-5900 4625) SIG_NAME M_D_CPU0_SB_DQS_DN<3>
J 0
(-5890 4635);
DISPLAY 0.659574 (-5890 4635);
PAINT MONO (-5890 4635);
DISPLAY INVISIBLE (-5890 4635);
FORCEPROP 1 LASTPIN (-5900 4625) BN 3
J 2
(-5888 4633);
DISPLAY 0.489362 (-5888 4633);
PAINT GREEN (-5888 4633);
FORCEPROP 2 LAST CDS_LIB mstr_standard
J 2
(-5950 4625);
DISPLAY 0.723404 (-5950 4625);
PAINT MONO (-5950 4625);
DISPLAY INVISIBLE (-5950 4625);
FORCEPROP 1 LAST BODY_TYPE PLUMBING
J 2
(-5950 4675);
DISPLAY 0.872340 (-5950 4675);
PAINT GREEN (-5950 4675);
DISPLAY INVISIBLE (-5950 4675);
FORCEPROP 1 LAST HDL_TAP TRUE
J 2
(-6275 4500);
DISPLAY 0.872340 (-6275 4500);
DISPLAY INVISIBLE (-6275 4500);
FORCEPROP 1 LAST PATH I271
J 2
(-5948 4625);
DISPLAY 0.872340 (-5948 4625);
PAINT GREEN (-5948 4625);
DISPLAY INVISIBLE (-5948 4625);
FORCEADD TAP..1
R 2
(-5750 4575);
FORCEPROP 3 LASTPIN (-5700 4575) SIG_NAME M_D_CPU0_SB_DQS_DP<4>
J 0
(-5690 4585);
DISPLAY 0.659574 (-5690 4585);
PAINT MONO (-5690 4585);
DISPLAY INVISIBLE (-5690 4585);
FORCEPROP 1 LASTPIN (-5700 4575) BN 4
J 2
(-5688 4583);
DISPLAY 0.489362 (-5688 4583);
PAINT GREEN (-5688 4583);
FORCEPROP 2 LAST CDS_LIB mstr_standard
J 2
(-5750 4575);
DISPLAY 0.723404 (-5750 4575);
PAINT MONO (-5750 4575);
DISPLAY INVISIBLE (-5750 4575);
FORCEPROP 1 LAST BODY_TYPE PLUMBING
J 2
(-5750 4625);
DISPLAY 0.872340 (-5750 4625);
PAINT GREEN (-5750 4625);
DISPLAY INVISIBLE (-5750 4625);
FORCEPROP 1 LAST HDL_TAP TRUE
J 2
(-6075 4450);
DISPLAY 0.872340 (-6075 4450);
DISPLAY INVISIBLE (-6075 4450);
FORCEPROP 1 LAST PATH I272
J 2
(-5748 4575);
DISPLAY 0.872340 (-5748 4575);
PAINT GREEN (-5748 4575);
DISPLAY INVISIBLE (-5748 4575);
FORCEADD TAP..1
R 2
(-5750 4475);
FORCEPROP 3 LASTPIN (-5700 4475) SIG_NAME M_D_CPU0_SB_DQS_DP<5>
J 0
(-5690 4485);
DISPLAY 0.659574 (-5690 4485);
PAINT MONO (-5690 4485);
DISPLAY INVISIBLE (-5690 4485);
FORCEPROP 1 LASTPIN (-5700 4475) BN 5
J 2
(-5688 4483);
DISPLAY 0.489362 (-5688 4483);
PAINT GREEN (-5688 4483);
FORCEPROP 2 LAST CDS_LIB mstr_standard
J 2
(-5750 4475);
DISPLAY 0.723404 (-5750 4475);
PAINT MONO (-5750 4475);
DISPLAY INVISIBLE (-5750 4475);
FORCEPROP 1 LAST BODY_TYPE PLUMBING
J 2
(-5750 4525);
DISPLAY 0.872340 (-5750 4525);
PAINT GREEN (-5750 4525);
DISPLAY INVISIBLE (-5750 4525);
FORCEPROP 1 LAST HDL_TAP TRUE
J 2
(-6075 4350);
DISPLAY 0.872340 (-6075 4350);
DISPLAY INVISIBLE (-6075 4350);
FORCEPROP 1 LAST PATH I273
J 2
(-5748 4475);
DISPLAY 0.872340 (-5748 4475);
PAINT GREEN (-5748 4475);
DISPLAY INVISIBLE (-5748 4475);
FORCEADD TAP..1
R 2
(-5750 4375);
FORCEPROP 3 LASTPIN (-5700 4375) SIG_NAME M_D_CPU0_SB_DQS_DP<6>
J 0
(-5690 4385);
DISPLAY 0.659574 (-5690 4385);
PAINT MONO (-5690 4385);
DISPLAY INVISIBLE (-5690 4385);
FORCEPROP 1 LASTPIN (-5700 4375) BN 6
J 2
(-5688 4383);
DISPLAY 0.489362 (-5688 4383);
PAINT GREEN (-5688 4383);
FORCEPROP 2 LAST CDS_LIB mstr_standard
J 2
(-5750 4375);
DISPLAY 0.723404 (-5750 4375);
PAINT MONO (-5750 4375);
DISPLAY INVISIBLE (-5750 4375);
FORCEPROP 1 LAST BODY_TYPE PLUMBING
J 2
(-5750 4425);
DISPLAY 0.872340 (-5750 4425);
PAINT GREEN (-5750 4425);
DISPLAY INVISIBLE (-5750 4425);
FORCEPROP 1 LAST HDL_TAP TRUE
J 2
(-6075 4250);
DISPLAY 0.872340 (-6075 4250);
DISPLAY INVISIBLE (-6075 4250);
FORCEPROP 1 LAST PATH I274
J 2
(-5748 4375);
DISPLAY 0.872340 (-5748 4375);
PAINT GREEN (-5748 4375);
DISPLAY INVISIBLE (-5748 4375);
FORCEADD TAP..1
R 2
(-5750 4275);
FORCEPROP 3 LASTPIN (-5700 4275) SIG_NAME M_D_CPU0_SB_DQS_DP<7>
J 0
(-5690 4285);
DISPLAY 0.659574 (-5690 4285);
PAINT MONO (-5690 4285);
DISPLAY INVISIBLE (-5690 4285);
FORCEPROP 1 LASTPIN (-5700 4275) BN 7
J 2
(-5688 4283);
DISPLAY 0.489362 (-5688 4283);
PAINT GREEN (-5688 4283);
FORCEPROP 2 LAST CDS_LIB mstr_standard
J 2
(-5750 4275);
DISPLAY 0.723404 (-5750 4275);
PAINT MONO (-5750 4275);
DISPLAY INVISIBLE (-5750 4275);
FORCEPROP 1 LAST BODY_TYPE PLUMBING
J 2
(-5750 4325);
DISPLAY 0.872340 (-5750 4325);
PAINT GREEN (-5750 4325);
DISPLAY INVISIBLE (-5750 4325);
FORCEPROP 1 LAST HDL_TAP TRUE
J 2
(-6075 4150);
DISPLAY 0.872340 (-6075 4150);
DISPLAY INVISIBLE (-6075 4150);
FORCEPROP 1 LAST PATH I275
J 2
(-5748 4275);
DISPLAY 0.872340 (-5748 4275);
PAINT GREEN (-5748 4275);
DISPLAY INVISIBLE (-5748 4275);
FORCEADD TAP..1
R 2
(-5750 4175);
FORCEPROP 3 LASTPIN (-5700 4175) SIG_NAME M_D_CPU0_SB_DQS_DP<8>
J 0
(-5690 4185);
DISPLAY 0.659574 (-5690 4185);
PAINT MONO (-5690 4185);
DISPLAY INVISIBLE (-5690 4185);
FORCEPROP 1 LASTPIN (-5700 4175) BN 8
J 2
(-5688 4183);
DISPLAY 0.489362 (-5688 4183);
PAINT GREEN (-5688 4183);
FORCEPROP 2 LAST CDS_LIB mstr_standard
J 2
(-5750 4175);
DISPLAY 0.723404 (-5750 4175);
PAINT MONO (-5750 4175);
DISPLAY INVISIBLE (-5750 4175);
FORCEPROP 1 LAST BODY_TYPE PLUMBING
J 2
(-5750 4225);
DISPLAY 0.872340 (-5750 4225);
PAINT GREEN (-5750 4225);
DISPLAY INVISIBLE (-5750 4225);
FORCEPROP 1 LAST HDL_TAP TRUE
J 2
(-6075 4050);
DISPLAY 0.872340 (-6075 4050);
DISPLAY INVISIBLE (-6075 4050);
FORCEPROP 1 LAST PATH I276
J 2
(-5748 4175);
DISPLAY 0.872340 (-5748 4175);
PAINT GREEN (-5748 4175);
DISPLAY INVISIBLE (-5748 4175);
FORCEADD TAP..1
R 2
(-5950 4525);
FORCEPROP 3 LASTPIN (-5900 4525) SIG_NAME M_D_CPU0_SB_DQS_DN<4>
J 0
(-5890 4535);
DISPLAY 0.659574 (-5890 4535);
PAINT MONO (-5890 4535);
DISPLAY INVISIBLE (-5890 4535);
FORCEPROP 1 LASTPIN (-5900 4525) BN 4
J 2
(-5888 4533);
DISPLAY 0.489362 (-5888 4533);
PAINT GREEN (-5888 4533);
FORCEPROP 2 LAST CDS_LIB mstr_standard
J 2
(-5950 4525);
DISPLAY 0.723404 (-5950 4525);
PAINT MONO (-5950 4525);
DISPLAY INVISIBLE (-5950 4525);
FORCEPROP 1 LAST BODY_TYPE PLUMBING
J 2
(-5950 4575);
DISPLAY 0.872340 (-5950 4575);
PAINT GREEN (-5950 4575);
DISPLAY INVISIBLE (-5950 4575);
FORCEPROP 1 LAST HDL_TAP TRUE
J 2
(-6275 4400);
DISPLAY 0.872340 (-6275 4400);
DISPLAY INVISIBLE (-6275 4400);
FORCEPROP 1 LAST PATH I277
J 2
(-5948 4525);
DISPLAY 0.872340 (-5948 4525);
PAINT GREEN (-5948 4525);
DISPLAY INVISIBLE (-5948 4525);
FORCEADD TAP..1
R 2
(-5950 4425);
FORCEPROP 3 LASTPIN (-5900 4425) SIG_NAME M_D_CPU0_SB_DQS_DN<5>
J 0
(-5890 4435);
DISPLAY 0.659574 (-5890 4435);
PAINT MONO (-5890 4435);
DISPLAY INVISIBLE (-5890 4435);
FORCEPROP 1 LASTPIN (-5900 4425) BN 5
J 2
(-5888 4433);
DISPLAY 0.489362 (-5888 4433);
PAINT GREEN (-5888 4433);
FORCEPROP 2 LAST CDS_LIB mstr_standard
J 2
(-5950 4425);
DISPLAY 0.723404 (-5950 4425);
PAINT MONO (-5950 4425);
DISPLAY INVISIBLE (-5950 4425);
FORCEPROP 1 LAST BODY_TYPE PLUMBING
J 2
(-5950 4475);
DISPLAY 0.872340 (-5950 4475);
PAINT GREEN (-5950 4475);
DISPLAY INVISIBLE (-5950 4475);
FORCEPROP 1 LAST HDL_TAP TRUE
J 2
(-6275 4300);
DISPLAY 0.872340 (-6275 4300);
DISPLAY INVISIBLE (-6275 4300);
FORCEPROP 1 LAST PATH I278
J 2
(-5948 4425);
DISPLAY 0.872340 (-5948 4425);
PAINT GREEN (-5948 4425);
DISPLAY INVISIBLE (-5948 4425);
FORCEADD TAP..1
R 2
(-5950 4325);
FORCEPROP 3 LASTPIN (-5900 4325) SIG_NAME M_D_CPU0_SB_DQS_DN<6>
J 0
(-5890 4335);
DISPLAY 0.659574 (-5890 4335);
PAINT MONO (-5890 4335);
DISPLAY INVISIBLE (-5890 4335);
FORCEPROP 1 LASTPIN (-5900 4325) BN 6
J 2
(-5888 4333);
DISPLAY 0.489362 (-5888 4333);
PAINT GREEN (-5888 4333);
FORCEPROP 2 LAST CDS_LIB mstr_standard
J 2
(-5950 4325);
DISPLAY 0.723404 (-5950 4325);
PAINT MONO (-5950 4325);
DISPLAY INVISIBLE (-5950 4325);
FORCEPROP 1 LAST BODY_TYPE PLUMBING
J 2
(-5950 4375);
DISPLAY 0.872340 (-5950 4375);
PAINT GREEN (-5950 4375);
DISPLAY INVISIBLE (-5950 4375);
FORCEPROP 1 LAST HDL_TAP TRUE
J 2
(-6275 4200);
DISPLAY 0.872340 (-6275 4200);
DISPLAY INVISIBLE (-6275 4200);
FORCEPROP 1 LAST PATH I279
J 2
(-5948 4325);
DISPLAY 0.872340 (-5948 4325);
PAINT GREEN (-5948 4325);
DISPLAY INVISIBLE (-5948 4325);
FORCEADD TAP..1
R 2
(-5950 4225);
FORCEPROP 3 LASTPIN (-5900 4225) SIG_NAME M_D_CPU0_SB_DQS_DN<7>
J 0
(-5890 4235);
DISPLAY 0.659574 (-5890 4235);
PAINT MONO (-5890 4235);
DISPLAY INVISIBLE (-5890 4235);
FORCEPROP 1 LASTPIN (-5900 4225) BN 7
J 2
(-5888 4233);
DISPLAY 0.489362 (-5888 4233);
PAINT GREEN (-5888 4233);
FORCEPROP 2 LAST CDS_LIB mstr_standard
J 2
(-5950 4225);
DISPLAY 0.723404 (-5950 4225);
PAINT MONO (-5950 4225);
DISPLAY INVISIBLE (-5950 4225);
FORCEPROP 1 LAST BODY_TYPE PLUMBING
J 2
(-5950 4275);
DISPLAY 0.872340 (-5950 4275);
PAINT GREEN (-5950 4275);
DISPLAY INVISIBLE (-5950 4275);
FORCEPROP 1 LAST HDL_TAP TRUE
J 2
(-6275 4100);
DISPLAY 0.872340 (-6275 4100);
DISPLAY INVISIBLE (-6275 4100);
FORCEPROP 1 LAST PATH I280
J 2
(-5948 4225);
DISPLAY 0.872340 (-5948 4225);
PAINT GREEN (-5948 4225);
DISPLAY INVISIBLE (-5948 4225);
FORCEADD TAP..1
R 2
(-5950 4125);
FORCEPROP 3 LASTPIN (-5900 4125) SIG_NAME M_D_CPU0_SB_DQS_DN<8>
J 0
(-5890 4135);
DISPLAY 0.659574 (-5890 4135);
PAINT MONO (-5890 4135);
DISPLAY INVISIBLE (-5890 4135);
FORCEPROP 1 LASTPIN (-5900 4125) BN 8
J 2
(-5888 4133);
DISPLAY 0.489362 (-5888 4133);
PAINT GREEN (-5888 4133);
FORCEPROP 2 LAST CDS_LIB mstr_standard
J 2
(-5950 4125);
DISPLAY 0.723404 (-5950 4125);
PAINT MONO (-5950 4125);
DISPLAY INVISIBLE (-5950 4125);
FORCEPROP 1 LAST BODY_TYPE PLUMBING
J 2
(-5950 4175);
DISPLAY 0.872340 (-5950 4175);
PAINT GREEN (-5950 4175);
DISPLAY INVISIBLE (-5950 4175);
FORCEPROP 1 LAST HDL_TAP TRUE
J 2
(-6275 4000);
DISPLAY 0.872340 (-6275 4000);
DISPLAY INVISIBLE (-6275 4000);
FORCEPROP 1 LAST PATH I281
J 2
(-5948 4125);
DISPLAY 0.872340 (-5948 4125);
PAINT GREEN (-5948 4125);
DISPLAY INVISIBLE (-5948 4125);
FORCEADD OFFPAGE..3
R 2
(-6650 6000);
FORCEPROP 2 LAST $XR0 88 
J 0
(-6899 6000);
DISPLAY 0.638298 (-6899 6000);
PAINT MONO (-6899 6000);
FORCEPROP 2 LAST PATH I282
J 0
(-6950 6050);
DISPLAY 1.021277 (-6950 6050);
DISPLAY INVISIBLE (-6950 6050);
FORCEPROP 1 LAST COMMENT_BODY TRUE
J 2
(-6600 5900);
DISPLAY 0.872340 (-6600 5900);
PAINT GREEN (-6600 5900);
DISPLAY INVISIBLE (-6600 5900);
FORCEPROP 1 LAST OFFPAGE TRUE
J 2
(-6975 5875);
DISPLAY 0.872340 (-6975 5875);
PAINT GREEN (-6975 5875);
DISPLAY INVISIBLE (-6975 5875);
FORCEPROP 2 LAST CDS_LIB standard
J 0
(-6650 6000);
DISPLAY INVISIBLE (-6650 6000);
FORCEADD OFFPAGE..3
R 2
(-6650 6050);
FORCEPROP 2 LAST $XR0 88 
J 0
(-6899 6050);
DISPLAY 0.638298 (-6899 6050);
PAINT MONO (-6899 6050);
FORCEPROP 2 LAST PATH I283
J 0
(-6950 6100);
DISPLAY 1.021277 (-6950 6100);
DISPLAY INVISIBLE (-6950 6100);
FORCEPROP 1 LAST COMMENT_BODY TRUE
J 2
(-6600 5950);
DISPLAY 0.872340 (-6600 5950);
PAINT GREEN (-6600 5950);
DISPLAY INVISIBLE (-6600 5950);
FORCEPROP 1 LAST OFFPAGE TRUE
J 2
(-6975 5925);
DISPLAY 0.872340 (-6975 5925);
PAINT GREEN (-6975 5925);
DISPLAY INVISIBLE (-6975 5925);
FORCEPROP 2 LAST CDS_LIB standard
J 0
(-6650 6050);
DISPLAY INVISIBLE (-6650 6050);
FORCEADD OFFPAGE..3
R 2
(-6650 4950);
FORCEPROP 2 LAST $XR0 88 
J 0
(-6899 4950);
DISPLAY 0.638298 (-6899 4950);
PAINT MONO (-6899 4950);
FORCEPROP 2 LAST PATH I284
J 0
(-6950 5000);
DISPLAY 1.021277 (-6950 5000);
DISPLAY INVISIBLE (-6950 5000);
FORCEPROP 1 LAST COMMENT_BODY TRUE
J 2
(-6600 4850);
DISPLAY 0.872340 (-6600 4850);
PAINT GREEN (-6600 4850);
DISPLAY INVISIBLE (-6600 4850);
FORCEPROP 1 LAST OFFPAGE TRUE
J 2
(-6975 4825);
DISPLAY 0.872340 (-6975 4825);
PAINT GREEN (-6975 4825);
DISPLAY INVISIBLE (-6975 4825);
FORCEPROP 2 LAST CDS_LIB standard
J 0
(-6650 4950);
DISPLAY INVISIBLE (-6650 4950);
FORCEADD OFFPAGE..3
R 2
(-6650 5000);
FORCEPROP 2 LAST $XR0 88 
J 0
(-6899 5000);
DISPLAY 0.638298 (-6899 5000);
PAINT MONO (-6899 5000);
FORCEPROP 2 LAST PATH I285
J 0
(-6950 5050);
DISPLAY 1.021277 (-6950 5050);
DISPLAY INVISIBLE (-6950 5050);
FORCEPROP 1 LAST COMMENT_BODY TRUE
J 2
(-6600 4900);
DISPLAY 0.872340 (-6600 4900);
PAINT GREEN (-6600 4900);
DISPLAY INVISIBLE (-6600 4900);
FORCEPROP 1 LAST OFFPAGE TRUE
J 2
(-6975 4875);
DISPLAY 0.872340 (-6975 4875);
PAINT GREEN (-6975 4875);
DISPLAY INVISIBLE (-6975 4875);
FORCEPROP 2 LAST CDS_LIB standard
J 0
(-6650 5000);
DISPLAY INVISIBLE (-6650 5000);
FORCEADD TAP..1
R 2
(-5750 4075);
FORCEPROP 3 LASTPIN (-5700 4075) SIG_NAME M_D_CPU0_SB_DQS_DP<9>
J 0
(-5690 4085);
DISPLAY 0.659574 (-5690 4085);
PAINT MONO (-5690 4085);
DISPLAY INVISIBLE (-5690 4085);
FORCEPROP 1 LASTPIN (-5700 4075) BN 9
J 2
(-5688 4083);
DISPLAY 0.489362 (-5688 4083);
PAINT GREEN (-5688 4083);
FORCEPROP 2 LAST CDS_LIB mstr_standard
J 2
(-5750 4075);
DISPLAY 0.723404 (-5750 4075);
PAINT MONO (-5750 4075);
DISPLAY INVISIBLE (-5750 4075);
FORCEPROP 1 LAST BODY_TYPE PLUMBING
J 2
(-5750 4125);
DISPLAY 0.872340 (-5750 4125);
PAINT GREEN (-5750 4125);
DISPLAY INVISIBLE (-5750 4125);
FORCEPROP 1 LAST HDL_TAP TRUE
J 2
(-6075 3950);
DISPLAY 0.872340 (-6075 3950);
DISPLAY INVISIBLE (-6075 3950);
FORCEPROP 1 LAST PATH I286
J 2
(-5748 4075);
DISPLAY 0.872340 (-5748 4075);
PAINT GREEN (-5748 4075);
DISPLAY INVISIBLE (-5748 4075);
FORCEADD TAP..1
R 2
(-5950 3825);
FORCEPROP 3 LASTPIN (-5900 3825) SIG_NAME M_D_CPU0_SA_CA<1>
J 0
(-5890 3835);
DISPLAY 0.659574 (-5890 3835);
PAINT MONO (-5890 3835);
DISPLAY INVISIBLE (-5890 3835);
FORCEPROP 1 LASTPIN (-5900 3825) BN 1
J 2
(-5888 3833);
DISPLAY 0.489362 (-5888 3833);
PAINT GREEN (-5888 3833);
FORCEPROP 2 LAST CDS_LIB mstr_standard
J 0
(-5950 3825);
DISPLAY 0.723404 (-5950 3825);
PAINT MONO (-5950 3825);
DISPLAY INVISIBLE (-5950 3825);
FORCEPROP 1 LAST BODY_TYPE PLUMBING
J 2
(-5950 3875);
DISPLAY 0.872340 (-5950 3875);
PAINT GREEN (-5950 3875);
DISPLAY INVISIBLE (-5950 3875);
FORCEPROP 1 LAST HDL_TAP TRUE
J 2
(-6275 3700);
DISPLAY 0.872340 (-6275 3700);
DISPLAY INVISIBLE (-6275 3700);
FORCEPROP 1 LAST PATH I287
J 2
(-5948 3825);
DISPLAY 0.872340 (-5948 3825);
PAINT GREEN (-5948 3825);
DISPLAY INVISIBLE (-5948 3825);
FORCEADD TAP..1
R 2
(-5950 4025);
FORCEPROP 3 LASTPIN (-5900 4025) SIG_NAME M_D_CPU0_SB_DQS_DN<9>
J 0
(-5890 4035);
DISPLAY 0.659574 (-5890 4035);
PAINT MONO (-5890 4035);
DISPLAY INVISIBLE (-5890 4035);
FORCEPROP 1 LASTPIN (-5900 4025) BN 9
J 2
(-5888 4033);
DISPLAY 0.489362 (-5888 4033);
PAINT GREEN (-5888 4033);
FORCEPROP 2 LAST CDS_LIB mstr_standard
J 2
(-5950 4025);
DISPLAY 0.723404 (-5950 4025);
PAINT MONO (-5950 4025);
DISPLAY INVISIBLE (-5950 4025);
FORCEPROP 1 LAST BODY_TYPE PLUMBING
J 2
(-5950 4075);
DISPLAY 0.872340 (-5950 4075);
PAINT GREEN (-5950 4075);
DISPLAY INVISIBLE (-5950 4075);
FORCEPROP 1 LAST HDL_TAP TRUE
J 2
(-6275 3900);
DISPLAY 0.872340 (-6275 3900);
DISPLAY INVISIBLE (-6275 3900);
FORCEPROP 1 LAST PATH I288
J 2
(-5948 4025);
DISPLAY 0.872340 (-5948 4025);
PAINT GREEN (-5948 4025);
DISPLAY INVISIBLE (-5948 4025);
FORCEADD TAP..1
R 2
(-5950 3875);
FORCEPROP 3 LASTPIN (-5900 3875) SIG_NAME M_D_CPU0_SA_CA<0>
J 0
(-5890 3885);
DISPLAY 0.659574 (-5890 3885);
PAINT MONO (-5890 3885);
DISPLAY INVISIBLE (-5890 3885);
FORCEPROP 1 LASTPIN (-5900 3875) BN 0
J 2
(-5888 3883);
DISPLAY 0.489362 (-5888 3883);
PAINT GREEN (-5888 3883);
FORCEPROP 2 LAST CDS_LIB mstr_standard
J 0
(-5950 3875);
DISPLAY 0.723404 (-5950 3875);
PAINT MONO (-5950 3875);
DISPLAY INVISIBLE (-5950 3875);
FORCEPROP 1 LAST BODY_TYPE PLUMBING
J 2
(-5950 3925);
DISPLAY 0.872340 (-5950 3925);
PAINT GREEN (-5950 3925);
DISPLAY INVISIBLE (-5950 3925);
FORCEPROP 1 LAST HDL_TAP TRUE
J 2
(-6275 3750);
DISPLAY 0.872340 (-6275 3750);
DISPLAY INVISIBLE (-6275 3750);
FORCEPROP 1 LAST PATH I289
J 2
(-5948 3875);
DISPLAY 0.872340 (-5948 3875);
PAINT GREEN (-5948 3875);
DISPLAY INVISIBLE (-5948 3875);
FORCEADD TAP..1
R 2
(-5950 3775);
FORCEPROP 3 LASTPIN (-5900 3775) SIG_NAME M_D_CPU0_SA_CA<2>
J 0
(-5890 3785);
DISPLAY 0.659574 (-5890 3785);
PAINT MONO (-5890 3785);
DISPLAY INVISIBLE (-5890 3785);
FORCEPROP 1 LASTPIN (-5900 3775) BN 2
J 2
(-5888 3783);
DISPLAY 0.489362 (-5888 3783);
PAINT GREEN (-5888 3783);
FORCEPROP 2 LAST CDS_LIB mstr_standard
J 0
(-5950 3775);
DISPLAY 0.723404 (-5950 3775);
PAINT MONO (-5950 3775);
DISPLAY INVISIBLE (-5950 3775);
FORCEPROP 1 LAST BODY_TYPE PLUMBING
J 2
(-5950 3825);
DISPLAY 0.872340 (-5950 3825);
PAINT GREEN (-5950 3825);
DISPLAY INVISIBLE (-5950 3825);
FORCEPROP 1 LAST HDL_TAP TRUE
J 2
(-6275 3650);
DISPLAY 0.872340 (-6275 3650);
DISPLAY INVISIBLE (-6275 3650);
FORCEPROP 1 LAST PATH I290
J 2
(-5948 3775);
DISPLAY 0.872340 (-5948 3775);
PAINT GREEN (-5948 3775);
DISPLAY INVISIBLE (-5948 3775);
FORCEADD TAP..1
R 2
(-5950 3725);
FORCEPROP 3 LASTPIN (-5900 3725) SIG_NAME M_D_CPU0_SA_CA<3>
J 0
(-5890 3735);
DISPLAY 0.659574 (-5890 3735);
PAINT MONO (-5890 3735);
DISPLAY INVISIBLE (-5890 3735);
FORCEPROP 1 LASTPIN (-5900 3725) BN 3
J 2
(-5888 3733);
DISPLAY 0.489362 (-5888 3733);
PAINT GREEN (-5888 3733);
FORCEPROP 2 LAST CDS_LIB mstr_standard
J 0
(-5950 3725);
DISPLAY 0.723404 (-5950 3725);
PAINT MONO (-5950 3725);
DISPLAY INVISIBLE (-5950 3725);
FORCEPROP 1 LAST BODY_TYPE PLUMBING
J 2
(-5950 3775);
DISPLAY 0.872340 (-5950 3775);
PAINT GREEN (-5950 3775);
DISPLAY INVISIBLE (-5950 3775);
FORCEPROP 1 LAST HDL_TAP TRUE
J 2
(-6275 3600);
DISPLAY 0.872340 (-6275 3600);
DISPLAY INVISIBLE (-6275 3600);
FORCEPROP 1 LAST PATH I291
J 2
(-5948 3725);
DISPLAY 0.872340 (-5948 3725);
PAINT GREEN (-5948 3725);
DISPLAY INVISIBLE (-5948 3725);
FORCEADD TAP..1
R 2
(-5950 3675);
FORCEPROP 3 LASTPIN (-5900 3675) SIG_NAME M_D_CPU0_SA_CA<4>
J 0
(-5890 3685);
DISPLAY 0.659574 (-5890 3685);
PAINT MONO (-5890 3685);
DISPLAY INVISIBLE (-5890 3685);
FORCEPROP 1 LASTPIN (-5900 3675) BN 4
J 2
(-5888 3683);
DISPLAY 0.489362 (-5888 3683);
PAINT GREEN (-5888 3683);
FORCEPROP 2 LAST CDS_LIB mstr_standard
J 0
(-5950 3675);
DISPLAY 0.723404 (-5950 3675);
PAINT MONO (-5950 3675);
DISPLAY INVISIBLE (-5950 3675);
FORCEPROP 1 LAST BODY_TYPE PLUMBING
J 2
(-5950 3725);
DISPLAY 0.872340 (-5950 3725);
PAINT GREEN (-5950 3725);
DISPLAY INVISIBLE (-5950 3725);
FORCEPROP 1 LAST HDL_TAP TRUE
J 2
(-6275 3550);
DISPLAY 0.872340 (-6275 3550);
DISPLAY INVISIBLE (-6275 3550);
FORCEPROP 1 LAST PATH I292
J 2
(-5948 3675);
DISPLAY 0.872340 (-5948 3675);
PAINT GREEN (-5948 3675);
DISPLAY INVISIBLE (-5948 3675);
FORCEADD TAP..1
R 2
(-5950 3625);
FORCEPROP 3 LASTPIN (-5900 3625) SIG_NAME M_D_CPU0_SA_CA<5>
J 0
(-5890 3635);
DISPLAY 0.659574 (-5890 3635);
PAINT MONO (-5890 3635);
DISPLAY INVISIBLE (-5890 3635);
FORCEPROP 1 LASTPIN (-5900 3625) BN 5
J 2
(-5888 3633);
DISPLAY 0.489362 (-5888 3633);
PAINT GREEN (-5888 3633);
FORCEPROP 2 LAST CDS_LIB mstr_standard
J 0
(-5950 3625);
DISPLAY 0.723404 (-5950 3625);
PAINT MONO (-5950 3625);
DISPLAY INVISIBLE (-5950 3625);
FORCEPROP 1 LAST BODY_TYPE PLUMBING
J 2
(-5950 3675);
DISPLAY 0.872340 (-5950 3675);
PAINT GREEN (-5950 3675);
DISPLAY INVISIBLE (-5950 3675);
FORCEPROP 1 LAST HDL_TAP TRUE
J 2
(-6275 3500);
DISPLAY 0.872340 (-6275 3500);
DISPLAY INVISIBLE (-6275 3500);
FORCEPROP 1 LAST PATH I293
J 2
(-5948 3625);
DISPLAY 0.872340 (-5948 3625);
PAINT GREEN (-5948 3625);
DISPLAY INVISIBLE (-5948 3625);
FORCEADD TAP..1
R 2
(-5950 3575);
FORCEPROP 3 LASTPIN (-5900 3575) SIG_NAME M_D_CPU0_SA_CA<6>
J 0
(-5890 3585);
DISPLAY 0.659574 (-5890 3585);
PAINT MONO (-5890 3585);
DISPLAY INVISIBLE (-5890 3585);
FORCEPROP 1 LASTPIN (-5900 3575) BN 6
J 2
(-5888 3583);
DISPLAY 0.489362 (-5888 3583);
PAINT GREEN (-5888 3583);
FORCEPROP 2 LAST CDS_LIB mstr_standard
J 0
(-5950 3575);
DISPLAY 0.723404 (-5950 3575);
PAINT MONO (-5950 3575);
DISPLAY INVISIBLE (-5950 3575);
FORCEPROP 1 LAST BODY_TYPE PLUMBING
J 2
(-5950 3625);
DISPLAY 0.872340 (-5950 3625);
PAINT GREEN (-5950 3625);
DISPLAY INVISIBLE (-5950 3625);
FORCEPROP 1 LAST HDL_TAP TRUE
J 2
(-6275 3450);
DISPLAY 0.872340 (-6275 3450);
DISPLAY INVISIBLE (-6275 3450);
FORCEPROP 1 LAST PATH I294
J 2
(-5948 3575);
DISPLAY 0.872340 (-5948 3575);
PAINT GREEN (-5948 3575);
DISPLAY INVISIBLE (-5948 3575);
FORCEADD TAP..1
R 2
(-5950 3425);
FORCEPROP 3 LASTPIN (-5900 3425) SIG_NAME M_D_CPU0_SB_CA<1>
J 0
(-5890 3435);
DISPLAY 0.659574 (-5890 3435);
PAINT MONO (-5890 3435);
DISPLAY INVISIBLE (-5890 3435);
FORCEPROP 1 LASTPIN (-5900 3425) BN 1
J 2
(-5888 3433);
DISPLAY 0.489362 (-5888 3433);
PAINT GREEN (-5888 3433);
FORCEPROP 2 LAST CDS_LIB mstr_standard
J 0
(-5950 3425);
DISPLAY 0.723404 (-5950 3425);
PAINT MONO (-5950 3425);
DISPLAY INVISIBLE (-5950 3425);
FORCEPROP 1 LAST BODY_TYPE PLUMBING
J 2
(-5950 3475);
DISPLAY 0.872340 (-5950 3475);
PAINT GREEN (-5950 3475);
DISPLAY INVISIBLE (-5950 3475);
FORCEPROP 1 LAST HDL_TAP TRUE
J 2
(-6275 3300);
DISPLAY 0.872340 (-6275 3300);
DISPLAY INVISIBLE (-6275 3300);
FORCEPROP 1 LAST PATH I295
J 2
(-5948 3425);
DISPLAY 0.872340 (-5948 3425);
PAINT GREEN (-5948 3425);
DISPLAY INVISIBLE (-5948 3425);
FORCEADD TAP..1
R 2
(-5950 3475);
FORCEPROP 3 LASTPIN (-5900 3475) SIG_NAME M_D_CPU0_SB_CA<0>
J 0
(-5890 3485);
DISPLAY 0.659574 (-5890 3485);
PAINT MONO (-5890 3485);
DISPLAY INVISIBLE (-5890 3485);
FORCEPROP 1 LASTPIN (-5900 3475) BN 0
J 2
(-5888 3483);
DISPLAY 0.489362 (-5888 3483);
PAINT GREEN (-5888 3483);
FORCEPROP 2 LAST CDS_LIB mstr_standard
J 0
(-5950 3475);
DISPLAY 0.723404 (-5950 3475);
PAINT MONO (-5950 3475);
DISPLAY INVISIBLE (-5950 3475);
FORCEPROP 1 LAST BODY_TYPE PLUMBING
J 2
(-5950 3525);
DISPLAY 0.872340 (-5950 3525);
PAINT GREEN (-5950 3525);
DISPLAY INVISIBLE (-5950 3525);
FORCEPROP 1 LAST HDL_TAP TRUE
J 2
(-6275 3350);
DISPLAY 0.872340 (-6275 3350);
DISPLAY INVISIBLE (-6275 3350);
FORCEPROP 1 LAST PATH I296
J 2
(-5948 3475);
DISPLAY 0.872340 (-5948 3475);
PAINT GREEN (-5948 3475);
DISPLAY INVISIBLE (-5948 3475);
FORCEADD TAP..1
R 2
(-5950 3325);
FORCEPROP 3 LASTPIN (-5900 3325) SIG_NAME M_D_CPU0_SB_CA<3>
J 0
(-5890 3335);
DISPLAY 0.659574 (-5890 3335);
PAINT MONO (-5890 3335);
DISPLAY INVISIBLE (-5890 3335);
FORCEPROP 1 LASTPIN (-5900 3325) BN 3
J 2
(-5888 3333);
DISPLAY 0.489362 (-5888 3333);
PAINT GREEN (-5888 3333);
FORCEPROP 2 LAST CDS_LIB mstr_standard
J 0
(-5950 3325);
DISPLAY 0.723404 (-5950 3325);
PAINT MONO (-5950 3325);
DISPLAY INVISIBLE (-5950 3325);
FORCEPROP 1 LAST BODY_TYPE PLUMBING
J 2
(-5950 3375);
DISPLAY 0.872340 (-5950 3375);
PAINT GREEN (-5950 3375);
DISPLAY INVISIBLE (-5950 3375);
FORCEPROP 1 LAST HDL_TAP TRUE
J 2
(-6275 3200);
DISPLAY 0.872340 (-6275 3200);
DISPLAY INVISIBLE (-6275 3200);
FORCEPROP 1 LAST PATH I297
J 2
(-5948 3325);
DISPLAY 0.872340 (-5948 3325);
PAINT GREEN (-5948 3325);
DISPLAY INVISIBLE (-5948 3325);
FORCEADD TAP..1
R 2
(-5950 3375);
FORCEPROP 3 LASTPIN (-5900 3375) SIG_NAME M_D_CPU0_SB_CA<2>
J 0
(-5890 3385);
DISPLAY 0.659574 (-5890 3385);
PAINT MONO (-5890 3385);
DISPLAY INVISIBLE (-5890 3385);
FORCEPROP 1 LASTPIN (-5900 3375) BN 2
J 2
(-5888 3383);
DISPLAY 0.489362 (-5888 3383);
PAINT GREEN (-5888 3383);
FORCEPROP 2 LAST CDS_LIB mstr_standard
J 0
(-5950 3375);
DISPLAY 0.723404 (-5950 3375);
PAINT MONO (-5950 3375);
DISPLAY INVISIBLE (-5950 3375);
FORCEPROP 1 LAST BODY_TYPE PLUMBING
J 2
(-5950 3425);
DISPLAY 0.872340 (-5950 3425);
PAINT GREEN (-5950 3425);
DISPLAY INVISIBLE (-5950 3425);
FORCEPROP 1 LAST HDL_TAP TRUE
J 2
(-6275 3250);
DISPLAY 0.872340 (-6275 3250);
DISPLAY INVISIBLE (-6275 3250);
FORCEPROP 1 LAST PATH I298
J 2
(-5948 3375);
DISPLAY 0.872340 (-5948 3375);
PAINT GREEN (-5948 3375);
DISPLAY INVISIBLE (-5948 3375);
FORCEADD TAP..1
R 2
(-5950 3275);
FORCEPROP 3 LASTPIN (-5900 3275) SIG_NAME M_D_CPU0_SB_CA<4>
J 0
(-5890 3285);
DISPLAY 0.659574 (-5890 3285);
PAINT MONO (-5890 3285);
DISPLAY INVISIBLE (-5890 3285);
FORCEPROP 1 LASTPIN (-5900 3275) BN 4
J 2
(-5888 3283);
DISPLAY 0.489362 (-5888 3283);
PAINT GREEN (-5888 3283);
FORCEPROP 2 LAST CDS_LIB mstr_standard
J 0
(-5950 3275);
DISPLAY 0.723404 (-5950 3275);
PAINT MONO (-5950 3275);
DISPLAY INVISIBLE (-5950 3275);
FORCEPROP 1 LAST BODY_TYPE PLUMBING
J 2
(-5950 3325);
DISPLAY 0.872340 (-5950 3325);
PAINT GREEN (-5950 3325);
DISPLAY INVISIBLE (-5950 3325);
FORCEPROP 1 LAST HDL_TAP TRUE
J 2
(-6275 3150);
DISPLAY 0.872340 (-6275 3150);
DISPLAY INVISIBLE (-6275 3150);
FORCEPROP 1 LAST PATH I299
J 2
(-5948 3275);
DISPLAY 0.872340 (-5948 3275);
PAINT GREEN (-5948 3275);
DISPLAY INVISIBLE (-5948 3275);
FORCEADD TAP..1
R 2
(-5950 3225);
FORCEPROP 3 LASTPIN (-5900 3225) SIG_NAME M_D_CPU0_SB_CA<5>
J 0
(-5890 3235);
DISPLAY 0.659574 (-5890 3235);
PAINT MONO (-5890 3235);
DISPLAY INVISIBLE (-5890 3235);
FORCEPROP 1 LASTPIN (-5900 3225) BN 5
J 2
(-5888 3233);
DISPLAY 0.489362 (-5888 3233);
PAINT GREEN (-5888 3233);
FORCEPROP 2 LAST CDS_LIB mstr_standard
J 0
(-5950 3225);
DISPLAY 0.723404 (-5950 3225);
PAINT MONO (-5950 3225);
DISPLAY INVISIBLE (-5950 3225);
FORCEPROP 1 LAST BODY_TYPE PLUMBING
J 2
(-5950 3275);
DISPLAY 0.872340 (-5950 3275);
PAINT GREEN (-5950 3275);
DISPLAY INVISIBLE (-5950 3275);
FORCEPROP 1 LAST HDL_TAP TRUE
J 2
(-6275 3100);
DISPLAY 0.872340 (-6275 3100);
DISPLAY INVISIBLE (-6275 3100);
FORCEPROP 1 LAST PATH I300
J 2
(-5948 3225);
DISPLAY 0.872340 (-5948 3225);
PAINT GREEN (-5948 3225);
DISPLAY INVISIBLE (-5948 3225);
FORCEADD TAP..1
R 2
(-5950 3175);
FORCEPROP 3 LASTPIN (-5900 3175) SIG_NAME M_D_CPU0_SB_CA<6>
J 0
(-5890 3185);
DISPLAY 0.659574 (-5890 3185);
PAINT MONO (-5890 3185);
DISPLAY INVISIBLE (-5890 3185);
FORCEPROP 1 LASTPIN (-5900 3175) BN 6
J 2
(-5888 3183);
DISPLAY 0.489362 (-5888 3183);
PAINT GREEN (-5888 3183);
FORCEPROP 2 LAST CDS_LIB mstr_standard
J 0
(-5950 3175);
DISPLAY 0.723404 (-5950 3175);
PAINT MONO (-5950 3175);
DISPLAY INVISIBLE (-5950 3175);
FORCEPROP 1 LAST BODY_TYPE PLUMBING
J 2
(-5950 3225);
DISPLAY 0.872340 (-5950 3225);
PAINT GREEN (-5950 3225);
DISPLAY INVISIBLE (-5950 3225);
FORCEPROP 1 LAST HDL_TAP TRUE
J 2
(-6275 3050);
DISPLAY 0.872340 (-6275 3050);
DISPLAY INVISIBLE (-6275 3050);
FORCEPROP 1 LAST PATH I301
J 2
(-5948 3175);
DISPLAY 0.872340 (-5948 3175);
PAINT GREEN (-5948 3175);
DISPLAY INVISIBLE (-5948 3175);
FORCEADD OFFPAGE..2
R 2
(-6550 3900);
FORCEPROP 2 LAST $XR0 88 
J 0
(-6774 3900);
DISPLAY 0.638298 (-6774 3900);
PAINT MONO (-6774 3900);
FORCEPROP 2 LAST PATH I302
J 0
(-6825 3950);
DISPLAY 1.021277 (-6825 3950);
DISPLAY INVISIBLE (-6825 3950);
FORCEPROP 1 LAST COMMENT_BODY TRUE
J 2
(-6505 3805);
DISPLAY 0.872340 (-6505 3805);
PAINT GREEN (-6505 3805);
DISPLAY INVISIBLE (-6505 3805);
FORCEPROP 1 LAST OFFPAGE TRUE
J 2
(-6875 3775);
DISPLAY 0.872340 (-6875 3775);
PAINT GREEN (-6875 3775);
DISPLAY INVISIBLE (-6875 3775);
FORCEPROP 2 LAST CDS_LIB standard
J 0
(-6550 3900);
DISPLAY INVISIBLE (-6550 3900);
FORCEADD OFFPAGE..2
R 2
(-6550 3500);
FORCEPROP 2 LAST $XR0 88 
J 0
(-6774 3500);
DISPLAY 0.638298 (-6774 3500);
PAINT MONO (-6774 3500);
FORCEPROP 2 LAST PATH I303
J 0
(-6825 3550);
DISPLAY 1.021277 (-6825 3550);
DISPLAY INVISIBLE (-6825 3550);
FORCEPROP 1 LAST COMMENT_BODY TRUE
J 2
(-6505 3405);
DISPLAY 0.872340 (-6505 3405);
PAINT GREEN (-6505 3405);
DISPLAY INVISIBLE (-6505 3405);
FORCEPROP 1 LAST OFFPAGE TRUE
J 2
(-6875 3375);
DISPLAY 0.872340 (-6875 3375);
PAINT GREEN (-6875 3375);
DISPLAY INVISIBLE (-6875 3375);
FORCEPROP 2 LAST CDS_LIB standard
J 0
(-6550 3500);
DISPLAY INVISIBLE (-6550 3500);
FORCEADD OFFPAGE..2
R 2
(-6550 3025);
FORCEPROP 2 LAST $XR0 88 
J 0
(-6774 3025);
DISPLAY 0.638298 (-6774 3025);
PAINT MONO (-6774 3025);
FORCEPROP 2 LAST PATH I304
J 0
(-6825 3075);
DISPLAY 1.021277 (-6825 3075);
DISPLAY INVISIBLE (-6825 3075);
FORCEPROP 1 LAST COMMENT_BODY TRUE
J 2
(-6505 2930);
DISPLAY 0.872340 (-6505 2930);
PAINT GREEN (-6505 2930);
DISPLAY INVISIBLE (-6505 2930);
FORCEPROP 1 LAST OFFPAGE TRUE
J 2
(-6875 2900);
DISPLAY 0.872340 (-6875 2900);
PAINT GREEN (-6875 2900);
DISPLAY INVISIBLE (-6875 2900);
FORCEPROP 2 LAST CDS_LIB standard
J 0
(-6550 3025);
DISPLAY INVISIBLE (-6550 3025);
FORCEADD OFFPAGE..2
R 2
(-6550 2975);
FORCEPROP 2 LAST $XR0 88 
J 0
(-6774 2975);
DISPLAY 0.638298 (-6774 2975);
PAINT MONO (-6774 2975);
FORCEPROP 2 LAST PATH I305
J 0
(-6825 3025);
DISPLAY 1.021277 (-6825 3025);
DISPLAY INVISIBLE (-6825 3025);
FORCEPROP 1 LAST COMMENT_BODY TRUE
J 2
(-6505 2880);
DISPLAY 0.872340 (-6505 2880);
PAINT GREEN (-6505 2880);
DISPLAY INVISIBLE (-6505 2880);
FORCEPROP 1 LAST OFFPAGE TRUE
J 2
(-6875 2850);
DISPLAY 0.872340 (-6875 2850);
PAINT GREEN (-6875 2850);
DISPLAY INVISIBLE (-6875 2850);
FORCEPROP 2 LAST CDS_LIB standard
J 0
(-6550 2975);
DISPLAY INVISIBLE (-6550 2975);
FORCEADD OFFPAGE..2
R 2
(-6550 2875);
FORCEPROP 2 LAST $XR0 88 
J 0
(-6774 2875);
DISPLAY 0.638298 (-6774 2875);
PAINT MONO (-6774 2875);
FORCEPROP 2 LAST PATH I306
J 0
(-6825 2925);
DISPLAY 1.021277 (-6825 2925);
DISPLAY INVISIBLE (-6825 2925);
FORCEPROP 1 LAST COMMENT_BODY TRUE
J 2
(-6505 2780);
DISPLAY 0.872340 (-6505 2780);
PAINT GREEN (-6505 2780);
DISPLAY INVISIBLE (-6505 2780);
FORCEPROP 1 LAST OFFPAGE TRUE
J 2
(-6875 2750);
DISPLAY 0.872340 (-6875 2750);
PAINT GREEN (-6875 2750);
DISPLAY INVISIBLE (-6875 2750);
FORCEPROP 2 LAST CDS_LIB standard
J 0
(-6550 2875);
DISPLAY INVISIBLE (-6550 2875);
FORCEADD OFFPAGE..2
R 2
(-6550 2825);
FORCEPROP 2 LAST $XR0 88 
J 0
(-6774 2825);
DISPLAY 0.638298 (-6774 2825);
PAINT MONO (-6774 2825);
FORCEPROP 2 LAST PATH I307
J 0
(-6825 2875);
DISPLAY 1.021277 (-6825 2875);
DISPLAY INVISIBLE (-6825 2875);
FORCEPROP 1 LAST COMMENT_BODY TRUE
J 2
(-6505 2730);
DISPLAY 0.872340 (-6505 2730);
PAINT GREEN (-6505 2730);
DISPLAY INVISIBLE (-6505 2730);
FORCEPROP 1 LAST OFFPAGE TRUE
J 2
(-6875 2700);
DISPLAY 0.872340 (-6875 2700);
PAINT GREEN (-6875 2700);
DISPLAY INVISIBLE (-6875 2700);
FORCEPROP 2 LAST CDS_LIB standard
J 0
(-6550 2825);
DISPLAY INVISIBLE (-6550 2825);
FORCEADD OFFPAGE..1
(-6550 2725);
FORCEPROP 2 LAST $XR0 88 
J 0
(-6801 2725);
DISPLAY 0.638298 (-6801 2725);
PAINT MONO (-6801 2725);
FORCEPROP 2 LAST PATH I308
J 0
(-6800 2775);
DISPLAY 1.021277 (-6800 2775);
DISPLAY INVISIBLE (-6800 2775);
FORCEPROP 1 LAST COMMENT_BODY TRUE
J 0
(-6425 2625);
DISPLAY 0.872340 (-6425 2625);
PAINT GREEN (-6425 2625);
DISPLAY INVISIBLE (-6425 2625);
FORCEPROP 1 LAST OFFPAGE TRUE
J 0
(-6225 2600);
DISPLAY 0.872340 (-6225 2600);
PAINT GREEN (-6225 2600);
DISPLAY INVISIBLE (-6225 2600);
FORCEPROP 2 LAST CDS_LIB standard
J 0
(-6550 2725);
DISPLAY INVISIBLE (-6550 2725);
FORCEADD OFFPAGE..5
(-6550 2625);
FORCEPROP 2 LAST $XR0 88 
J 0
(-6774 2625);
DISPLAY 0.638298 (-6774 2625);
PAINT MONO (-6774 2625);
FORCEPROP 2 LAST PATH I309
J 0
(-6825 2675);
DISPLAY 1.021277 (-6825 2675);
DISPLAY INVISIBLE (-6825 2675);
FORCEPROP 1 LAST COMMENT_BODY TRUE
J 0
(-6450 2550);
DISPLAY 0.872340 (-6450 2550);
PAINT GREEN (-6450 2550);
DISPLAY INVISIBLE (-6450 2550);
FORCEPROP 1 LAST OFFPAGE TRUE
J 0
(-6225 2500);
DISPLAY 0.872340 (-6225 2500);
PAINT GREEN (-6225 2500);
DISPLAY INVISIBLE (-6225 2500);
FORCEPROP 2 LAST CDS_LIB mstr_standard
J 0
(-6550 2625);
DISPLAY INVISIBLE (-6550 2625);
FORCEADD OFFPAGE..2
R 2
(-6550 2525);
FORCEPROP 2 LAST $XR0 88 
J 0
(-6774 2525);
DISPLAY 0.638298 (-6774 2525);
PAINT MONO (-6774 2525);
FORCEPROP 2 LAST PATH I310
J 0
(-6825 2575);
DISPLAY 1.021277 (-6825 2575);
DISPLAY INVISIBLE (-6825 2575);
FORCEPROP 1 LAST COMMENT_BODY TRUE
J 2
(-6505 2430);
DISPLAY 0.872340 (-6505 2430);
PAINT GREEN (-6505 2430);
DISPLAY INVISIBLE (-6505 2430);
FORCEPROP 1 LAST OFFPAGE TRUE
J 2
(-6875 2400);
DISPLAY 0.872340 (-6875 2400);
PAINT GREEN (-6875 2400);
DISPLAY INVISIBLE (-6875 2400);
FORCEPROP 2 LAST CDS_LIB standard
J 0
(-6550 2525);
DISPLAY INVISIBLE (-6550 2525);
FORCEADD OFFPAGE..2
R 2
(-6550 2475);
FORCEPROP 2 LAST $XR0 88 
J 0
(-6774 2475);
DISPLAY 0.638298 (-6774 2475);
PAINT MONO (-6774 2475);
FORCEPROP 2 LAST PATH I311
J 0
(-6825 2525);
DISPLAY 1.021277 (-6825 2525);
DISPLAY INVISIBLE (-6825 2525);
FORCEPROP 1 LAST COMMENT_BODY TRUE
J 2
(-6505 2380);
DISPLAY 0.872340 (-6505 2380);
PAINT GREEN (-6505 2380);
DISPLAY INVISIBLE (-6505 2380);
FORCEPROP 1 LAST OFFPAGE TRUE
J 2
(-6875 2350);
DISPLAY 0.872340 (-6875 2350);
PAINT GREEN (-6875 2350);
DISPLAY INVISIBLE (-6875 2350);
FORCEPROP 2 LAST CDS_LIB standard
J 0
(-6550 2475);
DISPLAY INVISIBLE (-6550 2475);
FORCEADD OFFPAGE..1
(-6550 2375);
FORCEPROP 2 LAST $XR0 88 
J 0
(-6801 2375);
DISPLAY 0.638298 (-6801 2375);
PAINT MONO (-6801 2375);
FORCEPROP 2 LAST PATH I312
J 0
(-6800 2425);
DISPLAY 1.021277 (-6800 2425);
DISPLAY INVISIBLE (-6800 2425);
FORCEPROP 1 LAST COMMENT_BODY TRUE
J 0
(-6425 2275);
DISPLAY 0.872340 (-6425 2275);
PAINT GREEN (-6425 2275);
DISPLAY INVISIBLE (-6425 2275);
FORCEPROP 1 LAST OFFPAGE TRUE
J 0
(-6225 2250);
DISPLAY 0.872340 (-6225 2250);
PAINT GREEN (-6225 2250);
DISPLAY INVISIBLE (-6225 2250);
FORCEPROP 2 LAST CDS_LIB standard
J 0
(-6550 2375);
DISPLAY INVISIBLE (-6550 2375);
FORCEADD OFFPAGE..5
(-6550 2275);
FORCEPROP 2 LAST $XR0 88 
J 0
(-6774 2275);
DISPLAY 0.638298 (-6774 2275);
PAINT MONO (-6774 2275);
FORCEPROP 2 LAST PATH I313
J 0
(-6825 2325);
DISPLAY 1.021277 (-6825 2325);
DISPLAY INVISIBLE (-6825 2325);
FORCEPROP 1 LAST COMMENT_BODY TRUE
J 0
(-6450 2200);
DISPLAY 0.872340 (-6450 2200);
PAINT GREEN (-6450 2200);
DISPLAY INVISIBLE (-6450 2200);
FORCEPROP 1 LAST OFFPAGE TRUE
J 0
(-6225 2150);
DISPLAY 0.872340 (-6225 2150);
PAINT GREEN (-6225 2150);
DISPLAY INVISIBLE (-6225 2150);
FORCEPROP 2 LAST CDS_LIB standard
J 0
(-6550 2275);
DISPLAY INVISIBLE (-6550 2275);
FORCEADD Q_RES..1
(-6875 2175);
FORCEPROP 1 LAST LOCATION R378
J 0
(-7200 2175);
DISPLAY 0.489362 (-7200 2175);
PAINT SKYBLUE (-7200 2175);
FORCEPROP 0 LAST $SEC 1
J 0
(-7050 2225);
DISPLAY 0.680851 (-7050 2225);
PAINT MONO (-7050 2225);
DISPLAY INVISIBLE (-7050 2225);
FORCEPROP 0 LAST CDS_SEC 1
J 0
(-7050 2225);
DISPLAY 1.021277 (-7050 2225);
DISPLAY INVISIBLE (-7050 2225);
FORCEPROP 1 LASTPIN (-6975 2175) $PN 1
J 0
(-6963 2187);
DISPLAY 0.489362 (-6963 2187);
PAINT MONO (-6963 2187);
FORCEPROP 1 LASTPIN (-6775 2175) $PN 2
J 0
(-6813 2187);
DISPLAY 0.489362 (-6813 2187);
PAINT MONO (-6813 2187);
FORCEPROP 1 LAST TOLERANCE 1%
J 0
(-6600 2175);
DISPLAY 0.489362 (-6600 2175);
PAINT SKYBLUE (-6600 2175);
FORCEPROP 1 LAST VALUE 15   
J 2
(-6550 2175);
DISPLAY 0.489362 (-6550 2175);
PAINT SKYBLUE (-6550 2175);
FORCEPROP 1 LAST PART_NUMBER CS01502FB11
J 0
(-6775 2150);
DISPLAY 0.489362 (-6775 2150);
PAINT SKYBLUE (-6775 2150);
FORCEPROP 1 LAST PACK_TYPE 0402LF
J 0
(-7200 2150);
DISPLAY 0.489362 (-7200 2150);
PAINT SKYBLUE (-7200 2150);
FORCEPROP 2 LAST CDS_LIB pure_quanta
J 0
(-6875 2175);
DISPLAY INVISIBLE (-6875 2175);
FORCEPROP 1 LAST PATH I314
J 0
(-6925 2325);
DISPLAY 0.978723 (-6925 2325);
PAINT WHITE (-6925 2325);
DISPLAY INVISIBLE (-6925 2325);
FORCEPROP 1 LAST WATTAGE 1/16W
J 2
(-6650 2300);
DISPLAY 0.638298 (-6650 2300);
PAINT SKYBLUE (-6650 2300);
DISPLAY INVISIBLE (-6650 2300);
FORCEPROP 1 LAST MATERIAL CHIP
J 0
(-7000 2300);
DISPLAY 0.638298 (-7000 2300);
PAINT SKYBLUE (-7000 2300);
DISPLAY INVISIBLE (-7000 2300);
FORCEADD OFFPAGE..1
(-7750 2175);
FORCEPROP 2 LAST $XR0 88 
J 0
(-7971 2175);
DISPLAY 0.638298 (-7971 2175);
PAINT MONO (-7971 2175);
FORCEPROP 2 LAST PATH I315
J 0
(-8025 2225);
DISPLAY 1.021277 (-8025 2225);
DISPLAY INVISIBLE (-8025 2225);
FORCEPROP 1 LAST COMMENT_BODY TRUE
J 0
(-7625 2075);
DISPLAY 0.872340 (-7625 2075);
PAINT GREEN (-7625 2075);
DISPLAY INVISIBLE (-7625 2075);
FORCEPROP 1 LAST OFFPAGE TRUE
J 0
(-7425 2050);
DISPLAY 0.872340 (-7425 2050);
PAINT GREEN (-7425 2050);
DISPLAY INVISIBLE (-7425 2050);
FORCEPROP 2 LAST CDS_LIB mstr_standard
J 0
(-7750 2175);
DISPLAY INVISIBLE (-7750 2175);
FORCEADD OFFPAGE..5
(-6550 2075);
FORCEPROP 2 LAST $XR0 88 
J 0
(-6774 2075);
DISPLAY 0.638298 (-6774 2075);
PAINT MONO (-6774 2075);
FORCEPROP 2 LAST PATH I316
J 0
(-6825 2125);
DISPLAY 1.021277 (-6825 2125);
DISPLAY INVISIBLE (-6825 2125);
FORCEPROP 1 LAST COMMENT_BODY TRUE
J 0
(-6450 2000);
DISPLAY 0.872340 (-6450 2000);
PAINT GREEN (-6450 2000);
DISPLAY INVISIBLE (-6450 2000);
FORCEPROP 1 LAST OFFPAGE TRUE
J 0
(-6225 1950);
DISPLAY 0.872340 (-6225 1950);
PAINT GREEN (-6225 1950);
DISPLAY INVISIBLE (-6225 1950);
FORCEPROP 2 LAST CDS_LIB standard
J 0
(-6550 2075);
DISPLAY INVISIBLE (-6550 2075);
FORCEADD QUANTA_TITLE_BLOCK_C..1
(-100 100);
FORCEPROP 0 LAST CDS_CON_LAST_MODIFIED Fri Mar 11 14:52:12 2022
J 0
(-1985 115);
DISPLAY INVISIBLE (-1985 115);
FORCEPROP 1 LAST CUSTOM_TXT_CDS <CON_LAST_MODIFIED>
J 0
(-1985 115);
DISPLAY 0.978723 (-1985 115);
FORCEPROP 2 LAST CUSTOM_TXT_CDS <XR_PAGE_TITLE>
J 0
(-7990 5350);
DISPLAY 0.638298 (-7990 5350);
PAINT PINK (-7990 5350);
DISPLAY INVISIBLE (-7990 5350);
FORCEPROP 1 LAST CUSTOM_TXT_CDS <NAME_2>
J 0
(-3275 150);
FORCEPROP 1 LAST CUSTOM_TXT_CDS <NAME_1>
J 0
(-3275 275);
FORCEPROP 1 LAST CUSTOM_TXT_CDS <Q_NUMBER>
J 0
(-1503 203);
DISPLAY 1.212766 (-1503 203);
FORCEPROP 1 LAST CUSTOM_TXT_CDS <Q_PROJ>
J 0
(-2482 202);
DISPLAY 1.212766 (-2482 202);
FORCEPROP 1 LAST CUSTOM_TXT_CDS <Q_REV>
J 0
(-284 203);
DISPLAY 1.212766 (-284 203);
FORCEPROP 1 LAST CUSTOM_TXT_CDS <CON_PAGE_NUM> OF <CON_TOTAL_PAGES>
J 0
(-546 118);
DISPLAY 0.978723 (-546 118);
FORCEPROP 1 LAST Q_TITLE CPU0 DDR CHD
J 0
(-9425 150);
DISPLAY 2.446809 (-9425 150);
PAINT GREEN (-9425 150);
FORCEPROP 1 LAST Q_DEPT BU9
J 1
(-3863 149);
DISPLAY 1.957447 (-3863 149);
PAINT GREEN (-3863 149);
FORCEPROP 2 LAST PAGE_BORDER TRUE
J 0
(-7990 5350);
DISPLAY 0.638298 (-7990 5350);
PAINT PINK (-7990 5350);
DISPLAY INVISIBLE (-7990 5350);
FORCEPROP 1 LAST CDS_LMAN_SYM_OUTLINE -9475,6775,100,-125
J 0
(-100 100);
DISPLAY 0.468085 (-100 100);
PAINT GREEN (-100 100);
DISPLAY INVISIBLE (-100 100);
FORCEPROP 2 LAST CDS_LIB pure_quanta
J 0
(-100 100);
DISPLAY INVISIBLE (-100 100);
FORCEPROP 1 LAST COMMENT_BODY TRUE
J 0
(-88 87);
DISPLAY 0.978723 (-88 87);
PAINT GREEN (-88 87);
DISPLAY INVISIBLE (-88 87);
FORCEPROP 2 LAST CDS_XR_PAGE_TITLE CR-13 : @T6G_MB_LIB.T6G(SCH_1):PAGE13
J 0
(-7990 5350);
DISPLAY 0.638298 (-7990 5350);
PAINT PINK (-7990 5350);
DISPLAY INVISIBLE (-7990 5350);
FORCEADD CAD_NOTE..1
(-7700 2475);
FORCEPROP 0 LAST L1 R1952 PLACE CLOSE TO CPU < 25MM
J 0
(-7850 2350);
DISPLAY 0.617021 (-7850 2350);
PAINT WHITE (-7850 2350);
FORCEPROP 2 LAST CDS_LIB pure_quanta_power
J 0
(-7700 2475);
DISPLAY INVISIBLE (-7700 2475);
FORCEPROP 1 LAST COMMENT_BODY TRUE
J 0
(-7675 2575);
DISPLAY 0.574468 (-7675 2575);
PAINT WHITE (-7675 2575);
DISPLAY INVISIBLE (-7675 2575);
WIRE 17 -1 (-3275 5900)(-3275 5850);
WIRE 17 -1 (-3275 5950)(-3275 5900);
WIRE 17 -1 (-3275 5850)(-3275 5800);
WIRE 17 -1 (-3275 5800)(-3275 5750);
WIRE 17 -1 (-3275 6000)(-3275 5950);
WIRE 17 -1 (-3275 6050)(-3275 6000);
WIRE 17 -1 (-3275 5750)(-3275 5700);
WIRE 17 -1 (-3275 5700)(-3275 5600);
WIRE 17 -1 (-3275 6050)(-2650 6050);
FORCEPROP 2 LAST SIG_NAME M_D_CPU0_SA_DQ<31:0>
J 2
(-2710 6060);
DISPLAY 0.489362 (-2710 6060);
WIRE 17 -1 (-3275 5600)(-3275 5550);
WIRE 17 -1 (-3275 5550)(-3275 5500);
WIRE 17 -1 (-3275 5500)(-3275 5450);
WIRE 17 -1 (-3275 5450)(-3275 5400);
WIRE 17 -1 (-3275 5400)(-3275 5350);
WIRE 17 -1 (-3275 5350)(-3275 5300);
WIRE 17 -1 (-3275 5300)(-3275 5250);
WIRE 17 -1 (-3275 5150)(-3275 5250);
WIRE 17 -1 (-3275 5100)(-3275 5150);
WIRE 17 -1 (-3275 5050)(-3275 5100);
WIRE 17 -1 (-3275 5000)(-3275 5050);
WIRE 17 -1 (-3275 5000)(-3275 4950);
WIRE 17 -1 (-3275 4950)(-3275 4900);
WIRE 17 -1 (-3275 4900)(-3275 4850);
WIRE 17 -1 (-3275 4850)(-3275 4800);
WIRE 17 -1 (-3275 4800)(-3275 4700);
WIRE 17 -1 (-3275 4700)(-3275 4650);
WIRE 17 -1 (-3275 4650)(-3275 4600);
WIRE 17 -1 (-3275 4600)(-3275 4550);
WIRE 17 -1 (-3275 4500)(-3275 4550);
WIRE 17 -1 (-3275 4450)(-3275 4500);
WIRE 17 -1 (-3275 4400)(-3275 4450);
WIRE 17 -1 (-3275 4350)(-3275 4400);
WIRE 17 -1 (-3275 4150)(-3275 4100);
WIRE 17 -1 (-3275 4200)(-3275 4150);
WIRE 17 -1 (-3275 4100)(-3275 4050);
WIRE 17 -1 (-3275 4050)(-3275 4000);
WIRE 17 -1 (-3275 4250)(-3275 4200);
WIRE 17 -1 (-3275 4250)(-2650 4250);
FORCEPROP 2 LAST SIG_NAME M_D_CPU0_SB_DQ<31:0>
J 2
(-2710 4260);
DISPLAY 0.489362 (-2710 4260);
WIRE 17 -1 (-3275 3600)(-3275 3550);
WIRE 17 -1 (-3275 3650)(-3275 3600);
WIRE 17 -1 (-3275 3550)(-3275 3500);
WIRE 17 -1 (-3275 3500)(-3275 3450);
WIRE 17 -1 (-3275 3700)(-3275 3650);
WIRE 17 -1 (-3275 3750)(-3275 3700);
WIRE 17 -1 (-3275 3350)(-3275 3450);
WIRE 17 -1 (-3275 3300)(-3275 3350);
WIRE 17 -1 (-3275 3800)(-3275 3750);
WIRE 17 -1 (-3275 3900)(-3275 3800);
WIRE 17 -1 (-3275 3250)(-3275 3300);
WIRE 17 -1 (-3275 3200)(-3275 3250);
WIRE 17 -1 (-3275 3950)(-3275 3900);
WIRE 17 -1 (-3275 4000)(-3275 3950);
WIRE 17 -1 (-3275 3200)(-3275 3150);
WIRE 17 -1 (-3275 3150)(-3275 3100);
WIRE 17 -1 (-3275 3100)(-3275 3050);
WIRE 17 -1 (-3275 3050)(-3275 3000);
WIRE 17 -1 (-3275 3000)(-3275 2900);
WIRE 17 -1 (-3275 2900)(-3275 2850);
WIRE 17 -1 (-3275 2850)(-3275 2800);
WIRE 17 -1 (-3275 2800)(-3275 2750);
WIRE 17 -1 (-3275 2700)(-3275 2750);
WIRE 17 -1 (-3275 2650)(-3275 2700);
WIRE 17 -1 (-3275 2600)(-3275 2650);
WIRE 17 -1 (-3275 2550)(-3275 2600);
WIRE 17 -1 (-3275 2450)(-3275 2400);
WIRE 17 -1 (-3275 2450)(-3275 2475);
WIRE 17 -1 (-3275 2350)(-3275 2400);
WIRE 17 -1 (-3275 2350)(-3275 2300);
WIRE 17 -1 (-3275 2475)(-2775 2475);
FORCEPROP 2 LAST SIG_NAME M_D_CPU0_SA_CB<7:0>
J 2
(-2775 2485);
DISPLAY 0.489362 (-2775 2485);
WIRE 17 -1 (-3275 2250)(-3275 2300);
WIRE 17 -1 (-3275 2200)(-3275 2250);
WIRE 17 -1 (-3275 2150)(-3275 2200);
WIRE 17 -1 (-3275 2100)(-3275 2150);
WIRE 17 -1 (-3275 1900)(-3275 1850);
WIRE 17 -1 (-3275 1900)(-3275 1950);
WIRE 17 -1 (-3275 1800)(-3275 1850);
WIRE 17 -1 (-3275 1750)(-3275 1800);
WIRE 17 -1 (-3275 2000)(-3275 1950);
WIRE 17 -1 (-3275 2000)(-3275 2025);
WIRE 17 -1 (-3275 1700)(-3275 1750);
WIRE 17 -1 (-3275 1650)(-3275 1700);
WIRE 17 -1 (-3275 2025)(-2775 2025);
FORCEPROP 2 LAST SIG_NAME M_D_CPU0_SB_CB<7:0>
J 2
(-2775 2035);
DISPLAY 0.489362 (-2775 2035);
WIRE 17 -1 (-6000 5500)(-6000 5600);
WIRE 17 -1 (-6000 5400)(-6000 5500);
WIRE 17 -1 (-6000 5700)(-6000 5600);
WIRE 17 -1 (-6000 5800)(-6000 5700);
WIRE 17 -1 (-6000 5300)(-6000 5400);
WIRE 17 -1 (-6000 5300)(-6000 5200);
WIRE 17 -1 (-6000 5900)(-6000 5800);
WIRE 17 -1 (-6000 6000)(-6000 5900);
FORCEPROP 2 LAST SIG_NAME M_D_CPU0_SA_DQS_DN<9:0>
J 2
(-6035 6010);
DISPLAY 0.489362 (-6035 6010);
WIRE 17 -1 (-5800 5950)(-5800 5850);
WIRE 17 -1 (-5800 6050)(-5800 5950);
WIRE 17 -1 (-5800 5850)(-5800 5750);
WIRE 17 -1 (-5800 5750)(-5800 5650);
WIRE 17 -1 (-5800 6050)(-6600 6050);
FORCEPROP 2 LAST SIG_NAME M_D_CPU0_SA_DQS_DP<9:0>
J 2
(-6035 6060);
DISPLAY 0.489362 (-6035 6060);
WIRE 17 -1 (-6000 5200)(-6000 5100);
WIRE 17 -1 (-5800 5550)(-5800 5650);
WIRE 17 -1 (-5800 5450)(-5800 5550);
WIRE 17 -1 (-5800 5350)(-5800 5450);
WIRE 17 -1 (-5800 5350)(-5800 5250);
WIRE 17 -1 (-5800 5250)(-5800 5150);
WIRE 17 -1 (-6000 4950)(-6000 4850);
FORCEPROP 2 LAST SIG_NAME M_D_CPU0_SB_DQS_DN<9:0>
J 2
(-6035 4960);
DISPLAY 0.489362 (-6035 4960);
WIRE 17 -1 (-6000 4750)(-6000 4650);
WIRE 17 -1 (-6000 4850)(-6000 4750);
WIRE 17 -1 (-6000 4650)(-6000 4550);
WIRE 17 -1 (-6000 4450)(-6000 4550);
WIRE 17 -1 (-6000 4350)(-6000 4450);
WIRE 17 -1 (-6000 4250)(-6000 4350);
WIRE 17 -1 (-6000 4250)(-6000 4150);
WIRE 17 -1 (-5800 5000)(-5800 4900);
WIRE 17 -1 (-5800 5000)(-6600 5000);
FORCEPROP 2 LAST SIG_NAME M_D_CPU0_SB_DQS_DP<9:0>
J 2
(-6035 5010);
DISPLAY 0.489362 (-6035 5010);
WIRE 17 -1 (-6000 4150)(-6000 4050);
WIRE 17 -1 (-5800 4900)(-5800 4800);
WIRE 17 -1 (-5800 4800)(-5800 4700);
WIRE 17 -1 (-5800 4700)(-5800 4600);
WIRE 17 -1 (-5800 4500)(-5800 4600);
WIRE 17 -1 (-5800 4400)(-5800 4500);
WIRE 17 -1 (-5800 4300)(-5800 4400);
WIRE 17 -1 (-5800 4300)(-5800 4200);
WIRE 17 -1 (-5800 4200)(-5800 4100);
WIRE 17 -1 (-6000 3850)(-6000 3900);
WIRE 17 -1 (-6000 3800)(-6000 3850);
WIRE 17 -1 (-6000 3900)(-6500 3900);
FORCEPROP 2 LAST SIG_NAME M_D_CPU0_SA_CA<6:0>
J 0
(-6500 3910);
DISPLAY 0.489362 (-6500 3910);
WIRE 17 -1 (-6000 3450)(-6000 3500);
WIRE 17 -1 (-6000 3400)(-6000 3450);
WIRE 17 -1 (-6000 3500)(-6500 3500);
FORCEPROP 2 LAST SIG_NAME M_D_CPU0_SB_CA<6:0>
J 0
(-6500 3510);
DISPLAY 0.489362 (-6500 3510);
WIRE 17 -1 (-6000 3750)(-6000 3800);
WIRE 17 -1 (-6000 3350)(-6000 3400);
WIRE 17 -1 (-6000 3700)(-6000 3750);
WIRE 17 -1 (-6000 3650)(-6000 3700);
WIRE 17 -1 (-6000 3600)(-6000 3650);
WIRE 17 -1 (-6000 3300)(-6000 3350);
WIRE 17 -1 (-6000 3250)(-6000 3300);
WIRE 17 -1 (-6000 3200)(-6000 3250);
WIRE 17 -1 (-6000 6000)(-6600 6000);
WIRE 17 -1 (-6000 4950)(-6600 4950);
WIRE 16 -1 (-7700 2175)(-6975 2175);
FORCEPROP 2 LAST SIG_NAME M_D_CPU0_ALERT_N
J 0
(-7660 2185);
DISPLAY 0.489362 (-7660 2185);
WIRE 16 -1 (-6500 1225)(-5400 1225);
FORCEPROP 2 LAST SIG_NAME TP_M_D_CPU0_SA_TEST39D
J 0
(-6485 1235);
DISPLAY 0.489362 (-6485 1235);
FORCEPROP 2 LASTPROP $XRERR UNIQUE?
J 0
(-6740 1225);
DISPLAY 0.638298 (-6740 1225);
PAINT MONO (-6740 1225);
DISPLAY INVISIBLE (-6740 1225);
WIRE 16 -1 (-6775 2175)(-5400 2175);
FORCEPROP 2 LAST SIG_NAME M_D_CPU0_ALERT_R_N
J 0
(-6485 2185);
DISPLAY 0.489362 (-6485 2185);
FORCEPROP 2 LASTPROP $XRERR UNIQUE?
J 0
(-6725 2185);
DISPLAY 0.638298 (-6725 2185);
PAINT MONO (-6725 2185);
DISPLAY INVISIBLE (-6725 2185);
WIRE 16 -1 (-6500 3025)(-5400 3025);
FORCEPROP 2 LAST SIG_NAME M_D_CPU0_CLK_DP<0>
J 0
(-6500 3035);
DISPLAY 0.489362 (-6500 3035);
WIRE 16 -1 (-6500 2975)(-5400 2975);
FORCEPROP 2 LAST SIG_NAME M_D_CPU0_CLK_DN<0>
J 0
(-6500 2985);
DISPLAY 0.489362 (-6500 2985);
WIRE 16 -1 (-6500 2875)(-5400 2875);
FORCEPROP 2 LAST SIG_NAME M_D_CPU0_SA_CS_N<0>
J 0
(-6500 2885);
DISPLAY 0.489362 (-6500 2885);
WIRE 16 -1 (-6500 2825)(-5400 2825);
FORCEPROP 2 LAST SIG_NAME M_D_CPU0_SA_CS_N<1>
J 0
(-6500 2835);
DISPLAY 0.489362 (-6500 2835);
WIRE 16 -1 (-6500 2725)(-5400 2725);
FORCEPROP 2 LAST SIG_NAME M_D_CPU0_SA_RSP<0>
J 0
(-6500 2735);
DISPLAY 0.489362 (-6500 2735);
WIRE 16 -1 (-6500 2625)(-5400 2625);
FORCEPROP 2 LAST SIG_NAME M_D_CPU0_SA_PAR
J 0
(-6500 2635);
DISPLAY 0.489362 (-6500 2635);
WIRE 16 -1 (-6500 2525)(-5400 2525);
FORCEPROP 2 LAST SIG_NAME M_D_CPU0_SB_CS_N<0>
J 0
(-6500 2535);
DISPLAY 0.489362 (-6500 2535);
WIRE 16 -1 (-6500 2475)(-5400 2475);
FORCEPROP 2 LAST SIG_NAME M_D_CPU0_SB_CS_N<1>
J 0
(-6500 2485);
DISPLAY 0.489362 (-6500 2485);
WIRE 16 -1 (-6500 2375)(-5400 2375);
FORCEPROP 2 LAST SIG_NAME M_D_CPU0_SB_RSP<0>
J 0
(-6500 2385);
DISPLAY 0.489362 (-6500 2385);
WIRE 16 -1 (-6500 2275)(-5400 2275);
FORCEPROP 2 LAST SIG_NAME M_D_CPU0_SB_PAR
J 0
(-6500 2285);
DISPLAY 0.489362 (-6500 2285);
WIRE 16 -1 (-6500 2075)(-5400 2075);
FORCEPROP 2 LAST SIG_NAME M_D_CPU0_RESET_N
J 0
(-6500 2085);
DISPLAY 0.489362 (-6500 2085);
WIRE 16 -1 (-5700 4075)(-5400 4075);
WIRE 16 -1 (-5900 3325)(-5400 3325);
WIRE 16 -1 (-5900 3175)(-5400 3175);
WIRE 16 -1 (-5900 3575)(-5400 3575);
WIRE 16 -1 (-5900 3225)(-5400 3225);
WIRE 16 -1 (-5900 3625)(-5400 3625);
WIRE 16 -1 (-5900 3275)(-5400 3275);
WIRE 16 -1 (-5900 3675)(-5400 3675);
WIRE 16 -1 (-5900 4025)(-5400 4025);
WIRE 16 -1 (-5900 3725)(-5400 3725);
WIRE 16 -1 (-5900 3375)(-5400 3375);
WIRE 16 -1 (-5900 3775)(-5400 3775);
WIRE 16 -1 (-5900 3425)(-5400 3425);
WIRE 16 -1 (-5900 3825)(-5400 3825);
WIRE 16 -1 (-5900 3475)(-5400 3475);
WIRE 16 -1 (-5900 3875)(-5400 3875);
WIRE 16 -1 (-5700 4175)(-5400 4175);
WIRE 16 -1 (-5700 4275)(-5400 4275);
WIRE 16 -1 (-5700 4375)(-5400 4375);
WIRE 16 -1 (-5700 4475)(-5400 4475);
WIRE 16 -1 (-5700 4575)(-5400 4575);
WIRE 16 -1 (-5900 4125)(-5400 4125);
WIRE 16 -1 (-5700 4675)(-5400 4675);
WIRE 16 -1 (-5900 4225)(-5400 4225);
WIRE 16 -1 (-5700 4775)(-5400 4775);
WIRE 16 -1 (-5900 4325)(-5400 4325);
WIRE 16 -1 (-5700 4875)(-5400 4875);
WIRE 16 -1 (-5900 4425)(-5400 4425);
WIRE 16 -1 (-5700 4975)(-5400 4975);
WIRE 16 -1 (-5900 4525)(-5400 4525);
WIRE 16 -1 (-5900 5075)(-5400 5075);
WIRE 16 -1 (-5900 4625)(-5400 4625);
WIRE 16 -1 (-5900 4725)(-5400 4725);
WIRE 16 -1 (-5900 4825)(-5400 4825);
WIRE 16 -1 (-5900 4925)(-5400 4925);
WIRE 16 -1 (-5700 6025)(-5400 6025);
WIRE 16 -1 (-5900 5575)(-5400 5575);
WIRE 16 -1 (-5900 5675)(-5400 5675);
WIRE 16 -1 (-5900 5775)(-5400 5775);
WIRE 16 -1 (-5900 5875)(-5400 5875);
WIRE 16 -1 (-5900 5975)(-5400 5975);
WIRE 16 -1 (-5700 5125)(-5400 5125);
WIRE 16 -1 (-5700 5225)(-5400 5225);
WIRE 16 -1 (-5700 5325)(-5400 5325);
WIRE 16 -1 (-5700 5425)(-5400 5425);
WIRE 16 -1 (-5700 5525)(-5400 5525);
WIRE 16 -1 (-5700 5625)(-5400 5625);
WIRE 16 -1 (-5900 5175)(-5400 5175);
WIRE 16 -1 (-5700 5725)(-5400 5725);
WIRE 16 -1 (-5900 5275)(-5400 5275);
WIRE 16 -1 (-5700 5825)(-5400 5825);
WIRE 16 -1 (-5900 5375)(-5400 5375);
WIRE 16 -1 (-5700 5925)(-5400 5925);
WIRE 16 -1 (-5900 5475)(-5400 5475);
WIRE 16 -1 (-3800 1875)(-3375 1875);
WIRE 16 -1 (-3800 1925)(-3375 1925);
WIRE 16 -1 (-3800 1975)(-3375 1975);
WIRE 16 -1 (-3800 1625)(-3375 1625);
WIRE 16 -1 (-3800 1675)(-3375 1675);
WIRE 16 -1 (-3800 1725)(-3375 1725);
WIRE 16 -1 (-3800 1775)(-3375 1775);
WIRE 16 -1 (-3800 1825)(-3375 1825);
WIRE 16 -1 (-3800 3025)(-3375 3025);
WIRE 16 -1 (-3375 2075)(-3800 2075);
WIRE 16 -1 (-3800 2125)(-3375 2125);
WIRE 16 -1 (-3800 2525)(-3375 2525);
WIRE 16 -1 (-3800 2175)(-3375 2175);
WIRE 16 -1 (-3800 2575)(-3375 2575);
WIRE 16 -1 (-3800 2225)(-3375 2225);
WIRE 16 -1 (-3800 2275)(-3375 2275);
WIRE 16 -1 (-3800 2325)(-3375 2325);
WIRE 16 -1 (-3800 2375)(-3375 2375);
WIRE 16 -1 (-3800 2425)(-3375 2425);
WIRE 16 -1 (-3800 2625)(-3375 2625);
WIRE 16 -1 (-3800 2675)(-3375 2675);
WIRE 16 -1 (-3800 2725)(-3375 2725);
WIRE 16 -1 (-3800 2775)(-3375 2775);
WIRE 16 -1 (-3800 2825)(-3375 2825);
WIRE 16 -1 (-3800 2875)(-3375 2875);
WIRE 16 -1 (-3800 2975)(-3375 2975);
WIRE 16 -1 (-3800 3625)(-3375 3625);
WIRE 16 -1 (-3800 3675)(-3375 3675);
WIRE 16 -1 (-3800 3075)(-3375 3075);
WIRE 16 -1 (-3800 3125)(-3375 3125);
WIRE 16 -1 (-3800 3725)(-3375 3725);
WIRE 16 -1 (-3800 3175)(-3375 3175);
WIRE 16 -1 (-3800 3775)(-3375 3775);
WIRE 16 -1 (-3800 3225)(-3375 3225);
WIRE 16 -1 (-3800 3875)(-3375 3875);
WIRE 16 -1 (-3800 3275)(-3375 3275);
WIRE 16 -1 (-3800 3925)(-3375 3925);
WIRE 16 -1 (-3800 3325)(-3375 3325);
WIRE 16 -1 (-3800 3975)(-3375 3975);
WIRE 16 -1 (-3800 3425)(-3375 3425);
WIRE 16 -1 (-3800 4025)(-3375 4025);
WIRE 16 -1 (-3800 3475)(-3375 3475);
WIRE 16 -1 (-3800 4075)(-3375 4075);
WIRE 16 -1 (-3800 3525)(-3375 3525);
WIRE 16 -1 (-3800 3575)(-3375 3575);
WIRE 16 -1 (-3800 5075)(-3375 5075);
WIRE 16 -1 (-3800 4475)(-3375 4475);
WIRE 16 -1 (-3800 4175)(-3375 4175);
WIRE 16 -1 (-3800 4525)(-3375 4525);
WIRE 16 -1 (-3800 4225)(-3375 4225);
WIRE 16 -1 (-3800 4575)(-3375 4575);
WIRE 16 -1 (-3800 4625)(-3375 4625);
WIRE 16 -1 (-3800 4675)(-3375 4675);
WIRE 16 -1 (-3800 4775)(-3375 4775);
WIRE 16 -1 (-3800 4825)(-3375 4825);
WIRE 16 -1 (-3800 4875)(-3375 4875);
WIRE 16 -1 (-3800 4925)(-3375 4925);
WIRE 16 -1 (-3800 4325)(-3375 4325);
WIRE 16 -1 (-3800 4375)(-3375 4375);
WIRE 16 -1 (-3800 4975)(-3375 4975);
WIRE 16 -1 (-3800 5025)(-3375 5025);
WIRE 16 -1 (-3800 4425)(-3375 4425);
WIRE 16 -1 (-3800 4125)(-3375 4125);
WIRE 16 -1 (-3800 5925)(-3375 5925);
WIRE 16 -1 (-3800 5975)(-3375 5975);
WIRE 16 -1 (-3800 5125)(-3375 5125);
WIRE 16 -1 (-3800 6025)(-3375 6025);
WIRE 16 -1 (-3800 5225)(-3375 5225);
WIRE 16 -1 (-3800 5275)(-3375 5275);
WIRE 16 -1 (-3800 5325)(-3375 5325);
WIRE 16 -1 (-3800 5375)(-3375 5375);
WIRE 16 -1 (-3800 5425)(-3375 5425);
WIRE 16 -1 (-3800 5475)(-3375 5475);
WIRE 16 -1 (-3800 5525)(-3375 5525);
WIRE 16 -1 (-3800 5575)(-3375 5575);
WIRE 16 -1 (-3800 5675)(-3375 5675);
WIRE 16 -1 (-3800 5725)(-3375 5725);
WIRE 16 -1 (-3800 5775)(-3375 5775);
WIRE 16 -1 (-3800 5825)(-3375 5825);
WIRE 16 -1 (-3800 5875)(-3375 5875);
QUIT
